G04 ================== begin FILE IDENTIFICATION RECORD ==================*
G04 Layout Name:  9048_F0T_Management_Board_D_brd_V04_1213_1625.brd*
G04 Film Name:    gnd1*
G04 File Format:  Gerber RS274X*
G04 File Origin:  Cadence Allegro 17.2-S081*
G04 Origin Date:  Tue Dec 13 16:31:11 2022*
G04 *
G04 Layer:  DRAWING FORMAT/TITLE_BLOCK_A*
G04 Layer:  VIA CLASS/GND1*
G04 Layer:  PIN/GND1*
G04 Layer:  MANUFACTURING/PHOTOPLOT_OUTLINE*
G04 Layer:  ETCH/GND1*
G04 Layer:  DRAWING FORMAT/TITLE_BLOCK*
G04 Layer:  DRAWING FORMAT/TITLE_DATA_GND1*
G04 *
G04 Offset:    (0.00 0.00)*
G04 Mirror:    No*
G04 Mode:      Negative*
G04 Rotation:  0*
G04 FullContactRelief:  No*
G04 UndefLineWidth:     6.00*
G04 ================== end FILE IDENTIFICATION RECORD ====================*
%FSLAX25Y25*MOIN*%
%IR0*IPPOS*OFA0.00000B0.00000*MIA0B0*SFA1.00000B1.00000*%
%ADD19C,.03*%
%ADD25C,.052*%
%ADD23C,.061*%
%ADD39C,.071*%
%ADD28C,.026*%
%AMMACRO37*
4,1,36,.0025,0.0,
.002462,.000434,
.002349,.000855,
.002165,.00125,
.001915,.001607,
.001607,.001915,
.00125,.002165,
.000855,.002349,
.000434,.002462,
0.0,.0025,
-.000434,.002462,
-.000855,.002349,
-.00125,.002165,
-.001607,.001915,
-.001915,.001607,
-.002165,.00125,
-.002349,.000855,
-.002462,.000434,
-.0025,0.0,
-.002462,-.000434,
-.002349,-.000855,
-.002165,-.00125,
-.001915,-.001607,
-.001607,-.001915,
-.00125,-.002165,
-.000855,-.002349,
-.000434,-.002462,
0.0,-.0025,
.000434,-.002462,
.000855,-.002349,
.00125,-.002165,
.001607,-.001915,
.001915,-.001607,
.002165,-.00125,
.002349,-.000855,
.002462,-.000434,
.0025,0.0,
315.*
%
%ADD37MACRO37*%
%AMMACRO22*
4,1,36,.0025,0.0,
.002462,.000434,
.002349,.000855,
.002165,.00125,
.001915,.001607,
.001607,.001915,
.00125,.002165,
.000855,.002349,
.000434,.002462,
0.0,.0025,
-.000434,.002462,
-.000855,.002349,
-.00125,.002165,
-.001607,.001915,
-.001915,.001607,
-.002165,.00125,
-.002349,.000855,
-.002462,.000434,
-.0025,0.0,
-.002462,-.000434,
-.002349,-.000855,
-.002165,-.00125,
-.001915,-.001607,
-.001607,-.001915,
-.00125,-.002165,
-.000855,-.002349,
-.000434,-.002462,
0.0,-.0025,
.000434,-.002462,
.000855,-.002349,
.00125,-.002165,
.001607,-.001915,
.001915,-.001607,
.002165,-.00125,
.002349,-.000855,
.002462,-.000434,
.0025,0.0,
180.*
%
%ADD22MACRO22*%
%AMMACRO14*
4,1,36,.0025,0.0,
.002462,.000434,
.002349,.000855,
.002165,.00125,
.001915,.001607,
.001607,.001915,
.00125,.002165,
.000855,.002349,
.000434,.002462,
0.0,.0025,
-.000434,.002462,
-.000855,.002349,
-.00125,.002165,
-.001607,.001915,
-.001915,.001607,
-.002165,.00125,
-.002349,.000855,
-.002462,.000434,
-.0025,0.0,
-.002462,-.000434,
-.002349,-.000855,
-.002165,-.00125,
-.001915,-.001607,
-.001607,-.001915,
-.00125,-.002165,
-.000855,-.002349,
-.000434,-.002462,
0.0,-.0025,
.000434,-.002462,
.000855,-.002349,
.00125,-.002165,
.001607,-.001915,
.001915,-.001607,
.002165,-.00125,
.002349,-.000855,
.002462,-.000434,
.0025,0.0,
270.*
%
%ADD14MACRO14*%
%AMMACRO41*
4,1,36,.003,0.0,
.002954,.000521,
.002819,.001026,
.002598,.0015,
.002298,.001928,
.001928,.002298,
.0015,.002598,
.001026,.002819,
.000521,.002954,
0.0,.003,
-.000521,.002954,
-.001026,.002819,
-.0015,.002598,
-.001928,.002298,
-.002298,.001928,
-.002598,.0015,
-.002819,.001026,
-.002954,.000521,
-.003,0.0,
-.002954,-.000521,
-.002819,-.001026,
-.002598,-.0015,
-.002298,-.001928,
-.001928,-.002298,
-.0015,-.002598,
-.001026,-.002819,
-.000521,-.002954,
0.0,-.003,
.000521,-.002954,
.001026,-.002819,
.0015,-.002598,
.001928,-.002298,
.002298,-.001928,
.002598,-.0015,
.002819,-.001026,
.002954,-.000521,
.003,0.0,
270.*
%
%ADD41MACRO41*%
%AMMACRO44*
4,1,36,-.003,0.0,
-.002954,.000521,
-.002819,.001026,
-.002598,.0015,
-.002298,.001928,
-.001928,.002298,
-.0015,.002598,
-.001026,.002819,
-.000521,.002954,
0.0,.003,
.000521,.002954,
.001026,.002819,
.0015,.002598,
.001928,.002298,
.002298,.001928,
.002598,.0015,
.002819,.001026,
.002954,.000521,
.003,0.0,
.002954,-.000521,
.002819,-.001026,
.002598,-.0015,
.002298,-.001928,
.001928,-.002298,
.0015,-.002598,
.001026,-.002819,
.000521,-.002954,
0.0,-.003,
-.000521,-.002954,
-.001026,-.002819,
-.0015,-.002598,
-.001928,-.002298,
-.002298,-.001928,
-.002598,-.0015,
-.002819,-.001026,
-.002954,-.000521,
-.003,0.0,
270.*
%
%ADD44MACRO44*%
%ADD40C,.0435*%
%ADD32C,.048*%
%AMMACRO31*
4,1,16,.04562,.02794,
.049779,.019594,
.052425,.010652,
.053478,.001387,
.052906,-.007921,
.050727,-.016987,
.047007,-.025538,
.04562,-.02794,
.0507,-.03302,
.055664,-.023714,
.058936,-.013688,
.060417,-.003246,
.060063,.007295,
.057884,.017614,
.053946,.027397,
.0507,.03302,
.04562,.02794,
90.*
4,1,16,.02794,-.04562,
.019594,-.049779,
.010652,-.052425,
.001387,-.053478,
-.007921,-.052906,
-.016987,-.050727,
-.025538,-.047007,
-.02794,-.04562,
-.03302,-.0507,
-.023714,-.055664,
-.013688,-.058936,
-.003246,-.060417,
.007295,-.060063,
.017614,-.057884,
.027397,-.053946,
.03302,-.0507,
.02794,-.04562,
90.*
4,1,16,-.04562,-.02794,
-.049779,-.019594,
-.052425,-.010652,
-.053478,-.001387,
-.052906,.007921,
-.050727,.016987,
-.047007,.025538,
-.04562,.02794,
-.0507,.03302,
-.055664,.023714,
-.058936,.013688,
-.060417,.003246,
-.060063,-.007295,
-.057884,-.017614,
-.053946,-.027397,
-.0507,-.03302,
-.04562,-.02794,
90.*
4,1,16,-.02794,.04562,
-.019594,.049779,
-.010652,.052425,
-.001387,.053478,
.007921,.052906,
.016987,.050727,
.025538,.047007,
.02794,.04562,
.03302,.0507,
.023714,.055664,
.013688,.058936,
.003246,.060417,
-.007295,.060063,
-.017614,.057884,
-.027397,.053946,
-.03302,.0507,
-.02794,.04562,
90.*
%
%ADD31MACRO31*%
%ADD15C,.066*%
%AMMACRO18*
4,1,14,.06158,.03329,
.066425,.022091,
.069252,.010221,
.069975,-.00196,
.068571,-.014081,
.065084,-.025775,
.06158,-.03329,
.06672,-.03844,
.072381,-.02627,
.075844,-.013302,
.077001,.00007,
.075819,.01344,
.072334,.026402,
.06672,.03844,
.06158,.03329,
0.0*
4,1,14,.03329,-.06158,
.022091,-.066425,
.010221,-.069252,
-.00196,-.069975,
-.014081,-.068571,
-.025775,-.065084,
-.03329,-.06158,
-.03844,-.06672,
-.02627,-.072381,
-.013302,-.075844,
.00007,-.077001,
.01344,-.075819,
.026402,-.072334,
.03844,-.06672,
.03329,-.06158,
0.0*
4,1,14,-.06158,-.03329,
-.066425,-.022091,
-.069252,-.010221,
-.069975,.00196,
-.068571,.014081,
-.065084,.025775,
-.06158,.03329,
-.06672,.03844,
-.072381,.02627,
-.075844,.013302,
-.077001,-.00007,
-.075819,-.01344,
-.072334,-.026402,
-.06672,-.03844,
-.06158,-.03329,
0.0*
4,1,14,-.03329,.06158,
-.022091,.066425,
-.010221,.069252,
.00196,.069975,
.014081,.068571,
.025775,.065084,
.03329,.06158,
.03844,.06672,
.02627,.072381,
.013302,.075844,
-.00007,.077001,
-.01344,.075819,
-.026402,.072334,
-.03844,.06672,
-.03329,.06158,
0.0*
%
%ADD18MACRO18*%
%AMMACRO36*
4,1,15,.06525,.03697,
.070678,.025078,
.073959,.012424,
.074993,-.000608,
.073748,-.013621,
.070263,-.026221,
.06525,-.03697,
.07037,-.04209,
.07661,-.029231,
.080522,-.015484,
.081987,-.001266,
.080961,.01299,
.077476,.026852,
.071636,.039897,
.07037,.04209,
.06525,.03697,
0.0*
4,1,15,.03697,-.06525,
.025078,-.070678,
.012424,-.073959,
-.000608,-.074993,
-.013621,-.073748,
-.026221,-.070263,
-.03697,-.06525,
-.04209,-.07037,
-.029231,-.07661,
-.015484,-.080522,
-.001266,-.081987,
.01299,-.080961,
.026852,-.077476,
.039897,-.071636,
.04209,-.07037,
.03697,-.06525,
0.0*
4,1,15,-.06525,-.03697,
-.070678,-.025078,
-.073959,-.012424,
-.074993,.000608,
-.073748,.013621,
-.070263,.026221,
-.06525,.03697,
-.07037,.04209,
-.07661,.029231,
-.080522,.015484,
-.081987,.001266,
-.080961,-.01299,
-.077476,-.026852,
-.071636,-.039897,
-.07037,-.04209,
-.06525,-.03697,
0.0*
4,1,15,-.03697,.06525,
-.025078,.070678,
-.012424,.073959,
.000608,.074993,
.013621,.073748,
.026221,.070263,
.03697,.06525,
.04209,.07037,
.029231,.07661,
.015484,.080522,
.001266,.081987,
-.01299,.080961,
-.026852,.077476,
-.039897,.071636,
-.04209,.07037,
-.03697,.06525,
0.0*
%
%ADD36MACRO36*%
%ADD26C,.078*%
%ADD11C,.087*%
%ADD33C,.097*%
%AMMACRO17*
4,1,15,.06231,.03403,
.067273,.022693,
.070191,.010666,
.070977,-.001684,
.069606,-.013984,
.066121,-.025858,
.06231,-.03403,
.06745,-.03917,
.073227,-.026862,
.076779,-.013739,
.077998,-.000197,
.076848,.01335,
.073362,.026492,
.067647,.038828,
.06745,.03917,
.06231,.03403,
0.0*
4,1,15,.03403,-.06231,
.022693,-.067273,
.010666,-.070191,
-.001684,-.070977,
-.013984,-.069606,
-.025858,-.066121,
-.03403,-.06231,
-.03917,-.06745,
-.026862,-.073227,
-.013739,-.076779,
-.000197,-.077998,
.01335,-.076848,
.026492,-.073362,
.038828,-.067647,
.03917,-.06745,
.03403,-.06231,
0.0*
4,1,15,-.06231,-.03403,
-.067273,-.022693,
-.070191,-.010666,
-.070977,.001684,
-.069606,.013984,
-.066121,.025858,
-.06231,.03403,
-.06745,.03917,
-.073227,.026862,
-.076779,.013739,
-.077998,.000197,
-.076848,-.01335,
-.073362,-.026492,
-.067647,-.038828,
-.06745,-.03917,
-.06231,-.03403,
0.0*
4,1,15,-.03403,.06231,
-.022693,.067273,
-.010666,.070191,
.001684,.070977,
.013984,.069606,
.025858,.066121,
.03403,.06231,
.03917,.06745,
.026862,.073227,
.013739,.076779,
.000197,.077998,
-.01335,.076848,
-.026492,.073362,
-.038828,.067647,
-.03917,.06745,
-.03403,.06231,
0.0*
%
%ADD17MACRO17*%
%AMMACRO30*
4,1,16,.0711,.04282,
.077455,.029823,
.081457,.01592,
.082984,.001533,
.08199,-.0129,
.078504,-.026942,
.072633,-.040164,
.0711,-.04282,
.07619,-.04791,
.083352,-.033952,
.087981,-.018962,
.089937,-.003396,
.089161,.012273,
.085675,.027569,
.079586,.042027,
.07619,.04791,
.0711,.04282,
0.0*
4,1,16,.04282,-.0711,
.029823,-.077455,
.01592,-.081457,
.001533,-.082984,
-.0129,-.08199,
-.026942,-.078504,
-.040164,-.072633,
-.04282,-.0711,
-.04791,-.07619,
-.033952,-.083352,
-.018962,-.087981,
-.003396,-.089937,
.012273,-.089161,
.027569,-.085675,
.042027,-.079586,
.04791,-.07619,
.04282,-.0711,
0.0*
4,1,16,-.0711,-.04282,
-.077455,-.029823,
-.081457,-.01592,
-.082984,-.001533,
-.08199,.0129,
-.078504,.026942,
-.072633,.040164,
-.0711,.04282,
-.07619,.04791,
-.083352,.033952,
-.087981,.018962,
-.089937,.003396,
-.089161,-.012273,
-.085675,-.027569,
-.079586,-.042027,
-.07619,-.04791,
-.0711,-.04282,
0.0*
4,1,16,-.04282,.0711,
-.029823,.077455,
-.01592,.081457,
-.001533,.082984,
.0129,.08199,
.026942,.078504,
.040164,.072633,
.04282,.0711,
.04791,.07619,
.033952,.083352,
.018962,.087981,
.003396,.089937,
-.012273,.089161,
-.027569,.085675,
-.042027,.079586,
-.04791,.07619,
-.04282,.0711,
0.0*
%
%ADD30MACRO30*%
%AMMACRO35*
4,1,15,.02142,.01082,
.022973,.006936,
.023829,.002841,
.02396,-.00134,
.023364,-.00548,
.022057,-.009454,
.02142,-.01082,
.02657,-.01597,
.02894,-.011114,
.03043,-.005919,
.030995,-.000545,
.030619,.004845,
.029313,.010088,
.027115,.015025,
.02657,.01597,
.02142,.01082,
0.0*
4,1,15,.01082,-.02142,
.006936,-.022973,
.002841,-.023829,
-.00134,-.02396,
-.00548,-.023364,
-.009454,-.022057,
-.01082,-.02142,
-.01597,-.02657,
-.011114,-.02894,
-.005919,-.03043,
-.000545,-.030995,
.004845,-.030619,
.010088,-.029313,
.015025,-.027115,
.01597,-.02657,
.01082,-.02142,
0.0*
4,1,15,-.02142,-.01082,
-.022973,-.006936,
-.023829,-.002841,
-.02396,.00134,
-.023364,.00548,
-.022057,.009454,
-.02142,.01082,
-.02657,.01597,
-.02894,.011114,
-.03043,.005919,
-.030995,.000545,
-.030619,-.004845,
-.029313,-.010088,
-.027115,-.015025,
-.02657,-.01597,
-.02142,-.01082,
0.0*
4,1,15,-.01082,.02142,
-.006936,.022973,
-.002841,.023829,
.00134,.02396,
.00548,.023364,
.009454,.022057,
.01082,.02142,
.01597,.02657,
.011114,.02894,
.005919,.03043,
.000545,.030995,
-.004845,.030619,
-.010088,.029313,
-.015025,.027115,
-.01597,.02657,
-.01082,.02142,
0.0*
%
%ADD35MACRO35*%
%AMMACRO34*
4,1,15,.01993,.00932,
.021246,.005718,
.021916,.001941,
.02192,-.001894,
.021258,-.005671,
.01995,-.009276,
.01993,-.00932,
.02511,-.01451,
.027248,-.009929,
.028558,-.005047,
.029001,-.000011,
.028562,.005025,
.027256,.009909,
.025121,.014491,
.02511,.01451,
.01993,.00932,
90.*
4,1,15,.00932,-.01993,
.005718,-.021246,
.001941,-.021916,
-.001894,-.02192,
-.005671,-.021258,
-.009276,-.01995,
-.00932,-.01993,
-.01451,-.02511,
-.009929,-.027248,
-.005047,-.028558,
-.000011,-.029001,
.005025,-.028562,
.009909,-.027256,
.014491,-.025121,
.01451,-.02511,
.00932,-.01993,
90.*
4,1,15,-.01993,-.00932,
-.021246,-.005718,
-.021916,-.001941,
-.02192,.001894,
-.021258,.005671,
-.01995,.009276,
-.01993,.00932,
-.02511,.01451,
-.027248,.009929,
-.028558,.005047,
-.029001,.000011,
-.028562,-.005025,
-.027256,-.009909,
-.025121,-.014491,
-.02511,-.01451,
-.01993,-.00932,
90.*
4,1,15,-.00932,.01993,
-.005718,.021246,
-.001941,.021916,
.001894,.02192,
.005671,.021258,
.009276,.01995,
.00932,.01993,
.01451,.02511,
.009929,.027248,
.005047,.028558,
.000011,.029001,
-.005025,.028562,
-.009909,.027256,
-.014491,.025121,
-.01451,.02511,
-.00932,.01993,
90.*
%
%ADD34MACRO34*%
%AMMACRO24*
4,1,15,.02475,.01414,
.026829,.009627,
.028094,.004822,
.028504,-.000129,
.028049,-.005077,
.026741,-.009871,
.02475,-.01414,
.02984,-.01923,
.032726,-.013756,
.034617,-.007864,
.035457,-.001734,
.03522,.00445,
.033912,.010498,
.031574,.016227,
.02984,.01923,
.02475,.01414,
0.0*
4,1,15,.01414,-.02475,
.009627,-.026829,
.004822,-.028094,
-.000129,-.028504,
-.005077,-.028049,
-.009871,-.026741,
-.01414,-.02475,
-.01923,-.02984,
-.013756,-.032726,
-.007864,-.034617,
-.001734,-.035457,
.00445,-.03522,
.010498,-.033912,
.016227,-.031574,
.01923,-.02984,
.01414,-.02475,
0.0*
4,1,15,-.02475,-.01414,
-.026829,-.009627,
-.028094,-.004822,
-.028504,.000129,
-.028049,.005077,
-.026741,.009871,
-.02475,.01414,
-.02984,.01923,
-.032726,.013756,
-.034617,.007864,
-.035457,.001734,
-.03522,-.00445,
-.033912,-.010498,
-.031574,-.016227,
-.02984,-.01923,
-.02475,-.01414,
0.0*
4,1,15,-.01414,.02475,
-.009627,.026829,
-.004822,.028094,
.000129,.028504,
.005077,.028049,
.009871,.026741,
.01414,.02475,
.01923,.02984,
.013756,.032726,
.007864,.034617,
.001734,.035457,
-.00445,.03522,
-.010498,.033912,
-.016227,.031574,
-.01923,.02984,
-.01414,.02475,
0.0*
%
%ADD24MACRO24*%
%AMMACRO10*
4,1,15,.03682,.01914,
.039584,.012455,
.041146,.005393,
.041457,-.001834,
.040509,-.009005,
.03833,-.015903,
.03682,-.01914,
.04197,-.0243,
.045552,-.016643,
.04775,-.00848,
.048497,-.000059,
.047771,.008363,
.045593,.016531,
.042029,.024197,
.04197,.0243,
.03682,.01914,
0.0*
4,1,15,.01914,-.03682,
.012455,-.039584,
.005393,-.041146,
-.001834,-.041457,
-.009005,-.040509,
-.015903,-.03833,
-.01914,-.03682,
-.0243,-.04197,
-.016643,-.045552,
-.00848,-.04775,
-.000059,-.048497,
.008363,-.047771,
.016531,-.045593,
.024197,-.042029,
.0243,-.04197,
.01914,-.03682,
0.0*
4,1,15,-.03682,-.01914,
-.039584,-.012455,
-.041146,-.005393,
-.041457,.001834,
-.040509,.009005,
-.03833,.015903,
-.03682,.01914,
-.04197,.0243,
-.045552,.016643,
-.04775,.00848,
-.048497,.000059,
-.047771,-.008363,
-.045593,-.016531,
-.042029,-.024197,
-.04197,-.0243,
-.03682,-.01914,
0.0*
4,1,15,-.01914,.03682,
-.012455,.039584,
-.005393,.041146,
.001834,.041457,
.009005,.040509,
.015903,.03833,
.01914,.03682,
.0243,.04197,
.016643,.045552,
.00848,.04775,
.000059,.048497,
-.008363,.047771,
-.016531,.045593,
-.024197,.042029,
-.0243,.04197,
-.01914,.03682,
0.0*
%
%ADD10MACRO10*%
%ADD29O,.156X.219*%
%ADD21C,.155*%
%AMMACRO38*
4,1,36,.0025,0.0,
.002462,.000434,
.002349,.000855,
.002165,.00125,
.001915,.001607,
.001607,.001915,
.00125,.002165,
.000855,.002349,
.000434,.002462,
0.0,.0025,
-.000434,.002462,
-.000855,.002349,
-.00125,.002165,
-.001607,.001915,
-.001915,.001607,
-.002165,.00125,
-.002349,.000855,
-.002462,.000434,
-.0025,0.0,
-.002462,-.000434,
-.002349,-.000855,
-.002165,-.00125,
-.001915,-.001607,
-.001607,-.001915,
-.00125,-.002165,
-.000855,-.002349,
-.000434,-.002462,
0.0,-.0025,
.000434,-.002462,
.000855,-.002349,
.00125,-.002165,
.001607,-.001915,
.001915,-.001607,
.002165,-.00125,
.002349,-.000855,
.002462,-.000434,
.0025,0.0,
45.*
%
%ADD38MACRO38*%
%AMMACRO20*
4,1,36,.0025,0.0,
.002462,.000434,
.002349,.000855,
.002165,.00125,
.001915,.001607,
.001607,.001915,
.00125,.002165,
.000855,.002349,
.000434,.002462,
0.0,.0025,
-.000434,.002462,
-.000855,.002349,
-.00125,.002165,
-.001607,.001915,
-.001915,.001607,
-.002165,.00125,
-.002349,.000855,
-.002462,.000434,
-.0025,0.0,
-.002462,-.000434,
-.002349,-.000855,
-.002165,-.00125,
-.001915,-.001607,
-.001607,-.001915,
-.00125,-.002165,
-.000855,-.002349,
-.000434,-.002462,
0.0,-.0025,
.000434,-.002462,
.000855,-.002349,
.00125,-.002165,
.001607,-.001915,
.001915,-.001607,
.002165,-.00125,
.002349,-.000855,
.002462,-.000434,
.0025,0.0,
90.*
%
%ADD20MACRO20*%
%AMMACRO42*
4,1,36,.003,0.0,
.002954,.000521,
.002819,.001026,
.002598,.0015,
.002298,.001928,
.001928,.002298,
.0015,.002598,
.001026,.002819,
.000521,.002954,
0.0,.003,
-.000521,.002954,
-.001026,.002819,
-.0015,.002598,
-.001928,.002298,
-.002298,.001928,
-.002598,.0015,
-.002819,.001026,
-.002954,.000521,
-.003,0.0,
-.002954,-.000521,
-.002819,-.001026,
-.002598,-.0015,
-.002298,-.001928,
-.001928,-.002298,
-.0015,-.002598,
-.001026,-.002819,
-.000521,-.002954,
0.0,-.003,
.000521,-.002954,
.001026,-.002819,
.0015,-.002598,
.001928,-.002298,
.002298,-.001928,
.002598,-.0015,
.002819,-.001026,
.002954,-.000521,
.003,0.0,
90.*
%
%ADD42MACRO42*%
%AMMACRO16*
4,1,36,.0025,0.0,
.002462,.000434,
.002349,.000855,
.002165,.00125,
.001915,.001607,
.001607,.001915,
.00125,.002165,
.000855,.002349,
.000434,.002462,
0.0,.0025,
-.000434,.002462,
-.000855,.002349,
-.00125,.002165,
-.001607,.001915,
-.001915,.001607,
-.002165,.00125,
-.002349,.000855,
-.002462,.000434,
-.0025,0.0,
-.002462,-.000434,
-.002349,-.000855,
-.002165,-.00125,
-.001915,-.001607,
-.001607,-.001915,
-.00125,-.002165,
-.000855,-.002349,
-.000434,-.002462,
0.0,-.0025,
.000434,-.002462,
.000855,-.002349,
.00125,-.002165,
.001607,-.001915,
.001915,-.001607,
.002165,-.00125,
.002349,-.000855,
.002462,-.000434,
.0025,0.0,
0.0*
%
%ADD16MACRO16*%
%AMMACRO43*
4,1,36,-.003,0.0,
-.002954,.000521,
-.002819,.001026,
-.002598,.0015,
-.002298,.001928,
-.001928,.002298,
-.0015,.002598,
-.001026,.002819,
-.000521,.002954,
0.0,.003,
.000521,.002954,
.001026,.002819,
.0015,.002598,
.001928,.002298,
.002298,.001928,
.002598,.0015,
.002819,.001026,
.002954,.000521,
.003,0.0,
.002954,-.000521,
.002819,-.001026,
.002598,-.0015,
.002298,-.001928,
.001928,-.002298,
.0015,-.002598,
.001026,-.002819,
.000521,-.002954,
0.0,-.003,
-.000521,-.002954,
-.001026,-.002819,
-.0015,-.002598,
-.001928,-.002298,
-.002298,-.001928,
-.002598,-.0015,
-.002819,-.001026,
-.002954,-.000521,
-.003,0.0,
90.*
%
%ADD43MACRO43*%
%AMMACRO27*
4,1,36,.0025,0.0,
.002462,.000434,
.002349,.000855,
.002165,.00125,
.001915,.001607,
.001607,.001915,
.00125,.002165,
.000855,.002349,
.000434,.002462,
0.0,.0025,
-.000434,.002462,
-.000855,.002349,
-.00125,.002165,
-.001607,.001915,
-.001915,.001607,
-.002165,.00125,
-.002349,.000855,
-.002462,.000434,
-.0025,0.0,
-.002462,-.000434,
-.002349,-.000855,
-.002165,-.00125,
-.001915,-.001607,
-.001607,-.001915,
-.00125,-.002165,
-.000855,-.002349,
-.000434,-.002462,
0.0,-.0025,
.000434,-.002462,
.000855,-.002349,
.00125,-.002165,
.001607,-.001915,
.001915,-.001607,
.002165,-.00125,
.002349,-.000855,
.002462,-.000434,
.0025,0.0,
84.*
%
%ADD27MACRO27*%
%AMMACRO13*
4,1,15,.03682,.01914,
.039584,.012455,
.041146,.005393,
.041457,-.001834,
.040509,-.009005,
.03833,-.015903,
.03682,-.01914,
.04197,-.0243,
.045552,-.016643,
.04775,-.00848,
.048497,-.000059,
.047771,.008363,
.045593,.016531,
.042029,.024197,
.04197,.0243,
.03682,.01914,
180.*
4,1,15,.01914,-.03682,
.012455,-.039584,
.005393,-.041146,
-.001834,-.041457,
-.009005,-.040509,
-.015903,-.03833,
-.01914,-.03682,
-.0243,-.04197,
-.016643,-.045552,
-.00848,-.04775,
-.000059,-.048497,
.008363,-.047771,
.016531,-.045593,
.024197,-.042029,
.0243,-.04197,
.01914,-.03682,
180.*
4,1,15,-.03682,-.01914,
-.039584,-.012455,
-.041146,-.005393,
-.041457,.001834,
-.040509,.009005,
-.03833,.015903,
-.03682,.01914,
-.04197,.0243,
-.045552,.016643,
-.04775,.00848,
-.048497,.000059,
-.047771,-.008363,
-.045593,-.016531,
-.042029,-.024197,
-.04197,-.0243,
-.03682,-.01914,
180.*
4,1,15,-.01914,.03682,
-.012455,.039584,
-.005393,.041146,
.001834,.041457,
.009005,.040509,
.015903,.03833,
.01914,.03682,
.0243,.04197,
.016643,.045552,
.00848,.04775,
.000059,.048497,
-.008363,.047771,
-.016531,.045593,
-.024197,.042029,
-.0243,.04197,
-.01914,.03682,
180.*
%
%ADD13MACRO13*%
%AMMACRO12*
4,1,15,-.03682,.01914,
-.039584,.012455,
-.041146,.005393,
-.041457,-.001834,
-.040509,-.009005,
-.03833,-.015903,
-.03682,-.01914,
-.04197,-.0243,
-.045552,-.016643,
-.04775,-.00848,
-.048497,-.000059,
-.047771,.008363,
-.045593,.016531,
-.042029,.024197,
-.04197,.0243,
-.03682,.01914,
180.*
4,1,15,-.01914,-.03682,
-.012455,-.039584,
-.005393,-.041146,
.001834,-.041457,
.009005,-.040509,
.015903,-.03833,
.01914,-.03682,
.0243,-.04197,
.016643,-.045552,
.00848,-.04775,
.000059,-.048497,
-.008363,-.047771,
-.016531,-.045593,
-.024197,-.042029,
-.0243,-.04197,
-.01914,-.03682,
180.*
4,1,15,.03682,-.01914,
.039584,-.012455,
.041146,-.005393,
.041457,.001834,
.040509,.009005,
.03833,.015903,
.03682,.01914,
.04197,.0243,
.045552,.016643,
.04775,.00848,
.048497,.000059,
.047771,-.008363,
.045593,-.016531,
.042029,-.024197,
.04197,-.0243,
.03682,-.01914,
180.*
4,1,15,.01914,.03682,
.012455,.039584,
.005393,.041146,
-.001834,.041457,
-.009005,.040509,
-.015903,.03833,
-.01914,.03682,
-.0243,.04197,
-.016643,.045552,
-.00848,.04775,
-.000059,.048497,
.008363,.047771,
.016531,.045593,
.024197,.042029,
.0243,.04197,
.01914,.03682,
180.*
%
%ADD12MACRO12*%
%ADD45C,.006*%
%ADD54C,.07306*%
%ADD51C,.08008*%
%ADD47C,.06807*%
%ADD53C,.06809*%
%ADD52C,.09908*%
%ADD49O,.03004X.06504*%
%ADD50O,.03006X.06506*%
%ADD46C,.16506*%
%ADD48O,.2363X.2993*%
G75*
%LPD*%
G75*
G36*
G01X-407000Y-793716D02*
X2010999D01*
Y1475775D01*
X-407000D01*
Y-793716D01*
G37*
%LPC*%
G75*
G36*
G01X-15748Y472016D02*
G02X-9874Y466142I0J-5874D01*
G01Y25945D01*
G02X-15748Y20071I-5874J0D01*
G01X-70000D01*
G02X-75874Y25945I0J5874D01*
G01Y466142D01*
G02X-70000Y472016I5874J0D01*
G01X-15748D01*
G37*
G36*
G01X2004Y336650D02*
Y442126D01*
G02X7874Y447996I5870J0D01*
G01X17717D01*
G03X21689Y451968I-1J3973D01*
G01Y467369D01*
X22132Y467812D01*
X23372D01*
X23781Y467404D01*
X38207D01*
X38828Y468024D01*
X40009D01*
X40378Y467655D01*
Y451968D01*
G03X44350Y447996I3973J1D01*
G01X50256D01*
G03X54228Y451968I-1J3973D01*
G01Y462100D01*
X122504D01*
Y451870D01*
G03X137339I7418J0D01*
G01Y462100D01*
X172543D01*
Y450098D01*
G03X183835I5646J0D01*
G01Y462100D01*
X252071D01*
Y450886D01*
G03X264937I6433J0D01*
G01Y462100D01*
X300122D01*
Y451968D01*
G03X304094Y447996I3973J1D01*
G01X310000D01*
G03X313973Y451969I0J3973D01*
G01Y467400D01*
X314385Y467812D01*
X315625D01*
X316034Y467404D01*
X330460D01*
X331081Y468024D01*
X332262D01*
X332642Y467644D01*
Y451968D01*
G03X336614Y447996I3973J1D01*
G01X346457D01*
G02X352327Y442126I0J-5870D01*
G01Y336650D01*
X345472D01*
G03X341500Y332678I0J-3973D01*
G01Y322834D01*
G03X345472Y318862I3972J0D01*
G01X352327D01*
Y271930D01*
X352331Y271926D01*
Y266763D01*
X352327Y266759D01*
Y7874D01*
G02X346457Y2004I-5870J0D01*
G01X7874D01*
G02X2004Y7874I0J5870D01*
G01Y242282D01*
X2000Y242286D01*
Y247986D01*
X2004Y247990D01*
Y318862D01*
X8858D01*
G03X12831Y322835I0J3973D01*
G01Y332677D01*
G03X8858Y336650I-3973J0D01*
G01X2004D01*
G37*
G36*
G01X364205Y466142D02*
G02X370079Y472016I5874J0D01*
G01X476378D01*
G02X482252Y466142I0J-5874D01*
G01Y-509842D01*
G02X476378Y-515716I-5874J0D01*
G01X370079D01*
G02X364205Y-509842I0J5874D01*
G01Y466142D01*
G37*
%LPD*%
G75*
G36*
G01X242870Y239000D02*
G02X243872Y238580I0J-1405D01*
G02Y236612I-853J-984D01*
G02X242870Y236192I-1002J985D01*
G02X242378Y236281I0J1404D01*
G01X242344Y236294D01*
X240395D01*
G02X239870Y236192I-525J1302D01*
G02Y239000I0J1404D01*
G02X240395Y238898I0J-1404D01*
G01X242344D01*
X242378Y238911D01*
G02X242870Y239000I492J-1315D01*
G37*
G36*
G01X239998Y225853D02*
Y229002D01*
G02X242602I1302J0D01*
G01Y226194D01*
G02X242638Y225890I-1264J-304D01*
G02X242261Y224974I-1301J0D01*
G02X241300Y224551I-961J880D01*
G02X239998Y225853I0J1302D01*
G37*
G36*
G01X250749Y236604D02*
X253898D01*
G02Y233998I0J-1303D01*
G01X250749D01*
G02Y236604I0J1303D01*
G37*
G36*
G01X253898Y233454D02*
X257047D01*
G02Y230848I0J-1303D01*
G01X253898D01*
G02Y233454I0J1303D01*
G37*
G36*
G01X153237Y61386D02*
X161111D01*
G02Y55780I0J-2803D01*
G01X153237D01*
G02Y61386I0J2803D01*
G37*
G36*
G01X165048Y55480D02*
X172922D01*
G02Y49874I0J-2803D01*
G01X165048D01*
G02Y55480I0J2803D01*
G37*
G36*
G01X176859Y61386D02*
X184733D01*
G02Y55780I0J-2803D01*
G01X176859D01*
G02Y61386I0J2803D01*
G37*
G36*
G01X244450Y233454D02*
X247599D01*
G02Y230848I0J-1303D01*
G01X244450D01*
G02Y233454I0J1303D01*
G37*
G36*
G01X250749Y230304D02*
X253898D01*
G02Y227700I0J-1302D01*
G01X250749D01*
G02Y230304I0J1302D01*
G37*
G36*
G01X162550Y385832D02*
X159050D01*
G02Y388836I0J1502D01*
G01X162550D01*
G02Y385832I0J-1502D01*
G37*
G36*
G01X72150Y425702D02*
X75650D01*
G02Y422696I0J-1503D01*
G01X72150D01*
G02Y425702I0J1503D01*
G37*
G36*
G01X92801Y454296D02*
X96301D01*
G02Y451290I0J-1503D01*
G01X92801D01*
G02Y454296I0J1503D01*
G37*
G36*
G01X60622Y432776D02*
X64122D01*
G02Y429770I0J-1503D01*
G01X60622D01*
G02Y432776I0J1503D01*
G37*
G36*
G01X182350Y384132D02*
X178850D01*
G02Y387136I0J1502D01*
G01X182350D01*
G02Y384132I0J-1502D01*
G37*
G36*
G01X216725Y440718D02*
X213225D01*
G02Y443722I0J1502D01*
G01X216725D01*
G02Y440718I0J-1502D01*
G37*
G36*
G01X159923Y97784D02*
X163423D01*
G02Y94778I0J-1503D01*
G01X159923D01*
G02Y97784I0J1503D01*
G37*
G36*
G01X169347D02*
X172847D01*
G02Y94778I0J-1503D01*
G01X169347D01*
G02Y97784I0J1503D01*
G37*
G36*
G01X221225Y408648D02*
X217725D01*
G02Y411652I0J1502D01*
G01X221225D01*
G02Y408648I0J-1502D01*
G37*
G36*
G01X267722Y175288D02*
X264222D01*
G02Y178294I0J1503D01*
G01X267722D01*
G02Y175288I0J-1503D01*
G37*
G36*
G01X81990Y449588D02*
X85490D01*
G02Y446582I0J-1503D01*
G01X81990D01*
G02Y449588I0J1503D01*
G37*
G36*
G01X52750Y425702D02*
X56250D01*
G02Y422698I0J-1502D01*
G01X52750D01*
G02Y425702I0J1502D01*
G37*
G36*
G01X255213Y107602D02*
X258713D01*
G02Y104596I0J-1503D01*
G01X255213D01*
G02Y107602I0J1503D01*
G37*
G36*
G01X246488Y107294D02*
X249988D01*
G02Y104290I0J-1502D01*
G01X246488D01*
G02Y107294I0J1502D01*
G37*
G36*
G01X266080Y205760D02*
X262580D01*
G02Y208764I0J1502D01*
G01X266080D01*
G02Y205760I0J-1502D01*
G37*
G36*
G01X267080Y213090D02*
X263580D01*
G02Y216096I0J1503D01*
G01X267080D01*
G02Y213090I0J-1503D01*
G37*
G36*
G01X95870Y446986D02*
X99370D01*
G02Y443980I0J-1503D01*
G01X95870D01*
G02Y446986I0J1503D01*
G37*
G36*
G01X375904Y-439648D02*
G02Y-436642I0J1503D01*
G01X379304D01*
G02Y-439648I0J-1503D01*
G01X375904D01*
G37*
G36*
G01X375964Y-217462D02*
G02Y-214456I0J1503D01*
G01X379364D01*
G02Y-217462I0J-1503D01*
G01X375964D01*
G37*
G36*
G01X375876Y-161376D02*
G02Y-158370I0J1503D01*
G01X379276D01*
G02Y-161376I0J-1503D01*
G01X375876D01*
G37*
G36*
G01X397080Y-122524D02*
G02Y-119518I0J1503D01*
G01X400480D01*
G02Y-122524I0J-1503D01*
G01X397080D01*
G37*
G36*
G01X375964Y10810D02*
G02Y13816I0J1503D01*
G01X379364D01*
G02Y10810I0J-1503D01*
G01X375964D01*
G37*
G36*
G01X375904Y66896D02*
G02Y69902I0J1503D01*
G01X379304D01*
G02Y66896I0J-1503D01*
G01X375904D01*
G37*
G36*
G01X375964Y380082D02*
G02Y383088I0J1503D01*
G01X379364D01*
G02Y380082I0J-1503D01*
G01X375964D01*
G37*
G36*
G01X396992Y-465710D02*
G02Y-462704I0J1503D01*
G01X400392D01*
G02Y-465710I0J-1503D01*
G01X396992D01*
G37*
G54D54*
X403692Y-481375D03*
X393692D03*
Y-456375D03*
X403692D03*
X382604Y-455313D03*
X372604D03*
Y-430313D03*
X382604D03*
X382664Y373753D03*
X372664D03*
Y398753D03*
X382664D03*
X393750Y272050D03*
X403750D03*
Y247050D03*
X393750D03*
Y200538D03*
X403750D03*
Y225538D03*
X393750D03*
X393780Y-128853D03*
X403780D03*
Y-103853D03*
X393780D03*
X403750Y-57222D03*
X393750D03*
Y-82222D03*
X403750D03*
X372604Y76231D03*
X382604D03*
Y51231D03*
X372604D03*
X413750Y-57222D03*
Y-82222D03*
X382664Y4481D03*
X372664D03*
Y29481D03*
X382664D03*
X403750Y398810D03*
X413750D03*
Y423810D03*
X403750D03*
X413750Y200538D03*
Y225538D03*
Y272050D03*
Y247050D03*
X372664Y-223791D03*
X382664D03*
Y-198791D03*
X372664D03*
X393750Y398810D03*
Y423810D03*
X372576Y-152041D03*
X382576D03*
Y-177041D03*
X372576D03*
G54D51*
X65945Y297776D03*
G54D47*
X45276Y18465D03*
X17716D03*
X264173Y20040D03*
X291733D03*
G54D53*
X309055Y18465D03*
X336615D03*
G54D52*
X144685Y297776D03*
G54D49*
X56482Y455094D03*
X102190Y64975D03*
G54D50*
X63569Y455094D03*
G54D46*
X-58189Y454331D03*
X340639Y432809D03*
X27300Y68200D03*
X464567Y-498031D03*
Y454331D03*
G54D48*
X105315Y186571D03*
G54D19*
X19200Y102700D03*
X12500Y102000D03*
X19100Y187420D03*
X15922Y224568D03*
Y227168D03*
X18422Y224568D03*
Y227168D03*
X17065Y255712D03*
X13736Y299891D03*
Y303280D03*
X13869Y352239D03*
X14000Y401700D03*
Y406700D03*
Y404200D03*
X17700Y427600D03*
X14600Y422500D03*
X14700Y425000D03*
X25200Y116300D03*
X31890Y110400D03*
X23736Y127758D03*
Y130758D03*
X32236Y127758D03*
Y130758D03*
X21000Y227000D03*
Y224500D03*
X24705Y258767D03*
X22237Y304626D03*
X30638Y304602D03*
X22237Y301237D03*
X30638Y301213D03*
X30700Y315500D03*
X33000Y318700D03*
X23810Y322534D03*
X31300Y329900D03*
X31000Y342500D03*
X26300Y374400D03*
X36200Y368400D03*
X31600Y379600D03*
X32700Y395381D03*
X20600Y428900D03*
X25202Y425329D03*
X29400Y430900D03*
X23677Y422419D03*
X31500Y428500D03*
X32100Y432800D03*
X45500Y41500D03*
X35304Y58317D03*
X45500Y92500D03*
X40340Y100710D03*
X45001Y95144D03*
X48500Y112559D03*
X40940D03*
X40736Y127758D03*
Y130758D03*
X49236Y127758D03*
Y130758D03*
X39408Y195990D03*
X47948Y201000D03*
X39900Y211000D03*
X39493Y222932D03*
X41993D03*
X44149Y227332D03*
X39493Y220332D03*
X41993D03*
X44149Y224732D03*
X48059Y214825D03*
X48023Y217860D03*
X39800Y213800D03*
X35700Y218000D03*
X35600Y241200D03*
Y238200D03*
X51500Y258200D03*
X37485Y258807D03*
X41100Y248900D03*
X46220Y277170D03*
X47440Y304225D03*
X39039Y301299D03*
X47440Y301336D03*
X39039Y304278D03*
X50950Y318050D03*
X43500Y317100D03*
X48420Y321616D03*
X44200Y332000D03*
X44525Y324000D03*
X39100Y321600D03*
X44481Y328760D03*
X38560Y329739D03*
X35500Y340500D03*
Y335000D03*
X44220Y341008D03*
X44500Y344000D03*
X37400Y359900D03*
X44500Y348000D03*
X44525Y360000D03*
X35100Y352400D03*
X44500Y351600D03*
X35900Y363025D03*
X37800Y371225D03*
X44525Y364000D03*
Y368000D03*
X37300Y375000D03*
X44525Y376000D03*
X37875Y377925D03*
X44525Y387800D03*
X37735Y391200D03*
X44525Y391650D03*
X35101Y381610D03*
X44525Y384000D03*
X37020Y385600D03*
X47075Y391730D03*
X44500Y380000D03*
X44490Y397850D03*
X44525Y394150D03*
X36911Y394915D03*
X37067Y398337D03*
X44341Y406480D03*
X44330Y401450D03*
X39530Y409100D03*
X42900Y412900D03*
X46100Y412700D03*
X41200Y429100D03*
X43600Y422800D03*
X42200Y435900D03*
X38000Y428800D03*
X48050Y436350D03*
X45100Y435800D03*
X46100Y422800D03*
X54200Y25400D03*
X58976Y36402D03*
X53600Y44100D03*
X56348Y36210D03*
X50710Y54724D03*
X55000Y76000D03*
X63086Y65762D03*
X52120Y78373D03*
X59240Y67242D03*
X52502Y80978D03*
X53434Y106562D03*
X53400Y102788D03*
X59945Y117795D03*
Y120630D03*
X52237Y129522D03*
X60800Y137000D03*
X61123Y133070D03*
X52876Y195712D03*
X52410Y186900D03*
X59700Y196200D03*
X52410Y190190D03*
X52050Y208760D03*
X64050Y201010D03*
X52948Y200700D03*
X58000Y217700D03*
X58823Y213531D03*
X51600Y241200D03*
X59850Y235830D03*
X51010Y233570D03*
X49700Y242900D03*
X50567Y238630D03*
X50700Y250400D03*
X61200Y282600D03*
X58900Y288075D03*
X54660Y311660D03*
X60613Y312012D03*
X60600Y318000D03*
X64230Y303210D03*
X56600Y320500D03*
Y324300D03*
X52800Y322400D03*
X63000Y324100D03*
X56600Y318000D03*
X52820Y325200D03*
X60225Y336099D03*
X57400Y345400D03*
X52900Y360000D03*
X52600Y376600D03*
X58035Y370100D03*
X54400Y374700D03*
X55294Y369729D03*
X52475Y364000D03*
X52765Y390200D03*
X59500Y394000D03*
X58620Y408779D03*
X63200Y408600D03*
X52330Y413350D03*
X59511Y424477D03*
X60622Y431273D03*
X64122D03*
X56250Y424200D03*
X52750D03*
X54100Y448600D03*
X56500Y447600D03*
X56482Y456844D03*
Y453344D03*
X63569Y456844D03*
Y453344D03*
X68500Y66500D03*
X75280Y75704D03*
X72500Y66500D03*
X74757Y89745D03*
Y92745D03*
Y86745D03*
Y83745D03*
X66830Y122329D03*
X66900Y125300D03*
X66874Y130590D03*
X72300Y159400D03*
X68600Y159160D03*
X76442Y166907D03*
X73550Y166680D03*
X67330Y169267D03*
X68960Y173300D03*
X75284Y180800D03*
X71124Y178565D03*
X75300Y183875D03*
X71146Y186489D03*
X71370Y188993D03*
X67386Y191935D03*
X67486Y188977D03*
X74046Y186490D03*
X71600Y200900D03*
X72150Y204810D03*
X76670Y208772D03*
X75000Y214000D03*
X72500D03*
X70453Y222900D03*
X74583Y217314D03*
X70900Y241500D03*
X71100Y233575D03*
X67700Y229725D03*
X68990Y257000D03*
X77010Y256645D03*
X65755Y256045D03*
X76200Y247400D03*
X73011Y246365D03*
X77384Y253769D03*
X68800Y253300D03*
X68990Y260465D03*
X77437Y262760D03*
X77900Y274700D03*
X70000Y280000D03*
X78600Y283970D03*
X75960Y284049D03*
X65100Y282475D03*
X72700Y301200D03*
X75870Y290700D03*
X78770Y290708D03*
X73400Y313700D03*
X77500Y316100D03*
X68500Y325100D03*
X81000Y321900D03*
X76900Y323000D03*
X76500Y325500D03*
X78700Y340000D03*
X78900Y336600D03*
X71700Y340600D03*
X71000Y394400D03*
X67900Y400525D03*
X79000Y395500D03*
X73976Y408665D03*
X77860Y408678D03*
X77592Y413437D03*
X69139Y413452D03*
X66319Y413492D03*
X74782Y413800D03*
X67000Y408800D03*
X69700D03*
X69030Y422653D03*
X68100Y425400D03*
X71200Y431700D03*
X72150Y424199D03*
X75650D03*
X77600Y431400D03*
X79010Y445750D03*
X72800Y437900D03*
X88000Y66500D03*
X84500D03*
X90151Y68985D03*
X91358Y89745D03*
Y92745D03*
Y86745D03*
Y83745D03*
X86700Y119100D03*
X92500Y116200D03*
X89256Y135056D03*
X86100Y153340D03*
X89170Y141540D03*
X89200Y138800D03*
X86100Y155840D03*
X83410Y161020D03*
X86100Y158390D03*
X83520Y158520D03*
X81500Y176515D03*
X80788Y190812D03*
X82370Y197010D03*
X91300Y252900D03*
X80300Y243700D03*
X80270Y247830D03*
X90800Y258225D03*
X83500Y266900D03*
X84016Y258230D03*
X91500Y267000D03*
X92300Y282100D03*
X90923Y293520D03*
X85500Y326700D03*
X92698Y323224D03*
X93288Y330289D03*
X81900Y337100D03*
X81700Y342600D03*
X90500Y397600D03*
X82500D03*
X89487Y408435D03*
X87600Y414500D03*
X87800Y410300D03*
X84801Y409760D03*
X92500Y408630D03*
X86481Y407871D03*
X96030Y409400D03*
X81552Y409660D03*
X84320Y430510D03*
X93259Y424200D03*
X88565Y426535D03*
X79600Y426400D03*
X81990Y448085D03*
X85490D03*
X92870Y437831D03*
X89700Y437900D03*
X92801Y452793D03*
X107000Y44500D03*
X102190Y63225D03*
X104600Y50501D03*
X98500Y66500D03*
X102190Y66725D03*
X111000Y77000D03*
X104500Y73500D03*
X107124Y71004D03*
X108800Y91900D03*
X104425Y82500D03*
X110950Y82050D03*
X106000Y91900D03*
X111075Y104600D03*
X100360Y116500D03*
X102999Y131799D03*
X108270Y138630D03*
X95950Y152900D03*
X95944Y149687D03*
X98720Y236980D03*
X103580Y237400D03*
X106600Y253689D03*
X95300Y247100D03*
X97177Y263320D03*
X102600Y267000D03*
X107200Y265000D03*
X106800Y262076D03*
X106574Y280028D03*
X106100Y282900D03*
X100700Y293600D03*
X108551Y294241D03*
X99990Y311200D03*
Y307900D03*
X105100Y309300D03*
X94400Y311100D03*
Y307200D03*
X100500Y328547D03*
X105755Y327719D03*
X103000Y323800D03*
X95060Y327625D03*
X106852Y323292D03*
X97800Y325700D03*
X99026Y338368D03*
X103180Y336286D03*
X108108Y395100D03*
X98100Y412400D03*
X105500Y418200D03*
X100457Y409100D03*
X108701Y418300D03*
X98300Y407600D03*
X108336Y411547D03*
X108500Y408680D03*
X109048Y425853D03*
X104112Y422946D03*
X103461Y425875D03*
X95845Y424755D03*
X106700Y447730D03*
X95770Y437920D03*
X95870Y445483D03*
X99370D03*
X103900Y447640D03*
X96301Y452793D03*
X119000Y44600D03*
X115000Y44500D03*
X125800Y47330D03*
X112800Y60400D03*
X112600Y52800D03*
X118500Y75500D03*
X116500Y74000D03*
X109121Y69500D03*
X119700Y89200D03*
X123710Y82300D03*
X123740Y79791D03*
X115025Y104800D03*
X123325Y111000D03*
X120724Y108937D03*
X109350Y115501D03*
X109200Y118500D03*
X120500Y115525D03*
X109200Y128500D03*
X118990Y131580D03*
X109670Y136060D03*
X118692Y137304D03*
X120800Y147200D03*
X117800D03*
X113000Y160700D03*
X115400Y159500D03*
X113000Y158000D03*
X122156Y157844D03*
X122900Y170100D03*
X123120Y213088D03*
X123790Y227656D03*
X123690Y230156D03*
X122876Y242800D03*
X117840Y242200D03*
X121200Y234890D03*
X112200Y234520D03*
X116143Y230790D03*
X112900Y239200D03*
X111400Y254680D03*
X122876Y245300D03*
X120020Y254430D03*
X119105Y251511D03*
X117400Y266500D03*
X109800Y264928D03*
X111600Y262730D03*
X111100Y273700D03*
X111600Y284000D03*
X120070Y273700D03*
X115000D03*
X122957Y300991D03*
X123100Y295974D03*
X120600Y293471D03*
X110565Y296331D03*
X124935Y324900D03*
X115535Y335235D03*
X124300Y348800D03*
X115600Y337900D03*
X114700Y351200D03*
X121200Y359200D03*
X111330Y357800D03*
X120200Y361600D03*
X114700Y348500D03*
X111460Y361770D03*
X111950Y371200D03*
X122047Y372260D03*
X125650Y368650D03*
X122330Y364670D03*
X111869Y365454D03*
X121175Y385125D03*
X119200Y389700D03*
X117410Y381350D03*
X110900Y378500D03*
X123100Y390600D03*
X119200Y406175D03*
X122600Y394600D03*
X119026Y393332D03*
X119791Y412301D03*
X112800Y421600D03*
X113000Y416200D03*
X116632Y411500D03*
X122498Y419675D03*
X112796Y412490D03*
X119500Y433600D03*
X111510Y434710D03*
X121700Y424005D03*
X123170Y433200D03*
X126425Y57000D03*
X133000Y59900D03*
X140730Y72600D03*
X130500Y74700D03*
X129300Y82650D03*
X131470Y81260D03*
X129500Y91475D03*
X131528Y114271D03*
X135500Y138000D03*
Y135000D03*
X134400Y127652D03*
X132828Y138400D03*
X133500Y146800D03*
X138458Y146458D03*
X132500Y167300D03*
X126500Y158000D03*
X133690Y158100D03*
X136190D03*
X126500Y174000D03*
X137900Y179160D03*
X135300Y175100D03*
X125700Y183700D03*
X129810Y191310D03*
X124338Y204742D03*
X124779Y201633D03*
X126153Y199079D03*
X135000Y221200D03*
X132500Y221900D03*
X138100Y213600D03*
X134891Y225171D03*
X124226Y225194D03*
X134358Y230069D03*
X130167Y234733D03*
X138000Y244600D03*
X133000Y256100D03*
X128760Y265726D03*
X127600Y259700D03*
X135315Y279813D03*
X125100Y273720D03*
X128760Y273701D03*
X137083Y278045D03*
X137196Y274491D03*
X132420Y273811D03*
X138600Y295900D03*
X124100Y311100D03*
X136100Y334000D03*
X129800Y325800D03*
X138590Y345710D03*
X124400Y345300D03*
X125910Y335006D03*
X125900Y337600D03*
X133300Y334100D03*
X136000Y341000D03*
X133000Y361500D03*
X132600Y350090D03*
X124350Y352450D03*
X129776Y374500D03*
X138700Y376600D03*
X126340Y382700D03*
X125174Y393916D03*
X135300Y399900D03*
X137900Y399500D03*
X131540Y394690D03*
X132700Y402700D03*
X133500Y409110D03*
X129135Y410250D03*
X133070Y420874D03*
X134300Y416414D03*
X136230Y423935D03*
X128866Y433066D03*
X135350Y433016D03*
X124500Y424005D03*
X132070Y433110D03*
X133572Y423935D03*
X125930Y433110D03*
X138750Y451500D03*
Y454500D03*
X152800Y75600D03*
X145000Y90700D03*
X145100Y87400D03*
X142400Y91300D03*
X141100Y86500D03*
X148819Y123197D03*
X143400Y121700D03*
X141220Y123070D03*
X147600Y117000D03*
X151800Y116500D03*
X152800Y111600D03*
X148819Y125697D03*
X149800Y138100D03*
Y135100D03*
X145185Y134214D03*
X142892Y136645D03*
X143269Y150456D03*
X150155Y145086D03*
X152556Y147683D03*
X148429Y147682D03*
X144500Y169570D03*
X146300Y161010D03*
X140554Y168887D03*
X153200Y170990D03*
X140554Y171688D03*
X146882Y177501D03*
X150619Y178646D03*
X145296Y188835D03*
X140830Y192530D03*
X153051Y187354D03*
X150005Y184973D03*
X149100Y189963D03*
X144280Y195130D03*
X151940Y203710D03*
X151900Y213200D03*
X143980Y199674D03*
X147800Y200789D03*
X140903Y199421D03*
X143742Y203395D03*
X152500Y199500D03*
X145500Y227700D03*
X142702Y227817D03*
X153100Y234800D03*
X149862Y243788D03*
X142085Y230549D03*
X151040Y237870D03*
X145250Y256890D03*
X145580Y248082D03*
X141280Y256310D03*
X149215Y267745D03*
X152400Y284400D03*
X150240Y277940D03*
X152500Y289425D03*
X150293Y302117D03*
X147500Y289405D03*
X141890Y310570D03*
X151320Y322700D03*
X148600Y336300D03*
X142202Y334000D03*
X142300Y336700D03*
X144800D03*
X144700Y334100D03*
X153419Y341978D03*
X143945Y354146D03*
X148316Y359086D03*
X141045Y355309D03*
X150900Y360325D03*
X151695Y357900D03*
X149500Y356700D03*
X141000Y358500D03*
X145703Y370700D03*
X139200Y372510D03*
X149000Y383070D03*
X152100Y378400D03*
X152500Y382600D03*
X150820Y387325D03*
X141520Y399700D03*
X139400Y392460D03*
X151265Y399500D03*
X142511Y393690D03*
X153079Y412000D03*
X149600Y410500D03*
X139700Y415100D03*
X150000Y414750D03*
X143000Y414600D03*
X140600Y412300D03*
X148060Y423500D03*
X148100Y433400D03*
X152200Y423100D03*
X148041Y426700D03*
X138987Y423935D03*
X151398Y449930D03*
X158246Y78872D03*
X156710Y73420D03*
X163423Y96281D03*
X159923D03*
X166200Y105500D03*
X155530Y116640D03*
X156286Y124903D03*
X156200Y111600D03*
X162657Y117297D03*
X154050Y137100D03*
X159000Y135000D03*
X166700Y132360D03*
X156406Y129203D03*
X162419Y131032D03*
X166733Y128700D03*
X155325Y139440D03*
X153954Y145086D03*
X161900Y150500D03*
X165690Y149622D03*
X159328Y160847D03*
X156481Y155933D03*
X162200Y158200D03*
X159900Y155600D03*
X161240Y177820D03*
X161237Y181735D03*
X156467Y203500D03*
X162594Y212585D03*
Y210085D03*
X166140Y205955D03*
X165381Y201274D03*
X153744Y217435D03*
X153800Y214900D03*
X162653Y218843D03*
X159643Y226484D03*
X162200Y221376D03*
X163500Y229184D03*
X167200Y222600D03*
X161200Y233600D03*
X165500Y236100D03*
X157200Y240000D03*
X156970Y255000D03*
X165013Y254986D03*
X160973D03*
X164500Y266000D03*
X160590Y263300D03*
X156970Y263250D03*
X164800Y263300D03*
X158750Y284949D03*
X168392Y298493D03*
X160850Y301344D03*
X168300Y301100D03*
X162100Y291600D03*
X161400Y307600D03*
X162160Y313560D03*
X170800Y317600D03*
X164500Y314800D03*
X155000Y321100D03*
X168557Y341221D03*
X158459Y340898D03*
X158467Y344067D03*
X161300Y354600D03*
X161154Y376704D03*
X156300Y376300D03*
X154500Y387350D03*
X159050Y387334D03*
X162550D03*
X165500Y386000D03*
X165501Y382800D03*
X158200Y381400D03*
X155452Y401000D03*
X160540Y416912D03*
X162100Y414000D03*
X157294Y435623D03*
X156101Y425100D03*
X167008Y430718D03*
X165500Y433100D03*
X167865Y427771D03*
X163700Y422119D03*
X159396Y449408D03*
X160700Y445550D03*
X158100Y442700D03*
X168029Y456660D03*
X157500Y453390D03*
X176900Y14625D03*
X178200Y76145D03*
X175700Y76245D03*
X179900Y91300D03*
X181960Y99260D03*
X169700Y102250D03*
X176300Y98700D03*
X172847Y96281D03*
X169347D03*
X179500Y116800D03*
X182000Y117200D03*
X171600Y114000D03*
X182865Y113706D03*
X174600Y114000D03*
X169100Y113900D03*
X182103Y132294D03*
X182108Y129094D03*
X170867Y128211D03*
X178290Y128824D03*
X174553Y128728D03*
X176550Y125210D03*
X178284Y132394D03*
X170610Y131900D03*
X174436Y132394D03*
X168800Y126800D03*
X172100Y146300D03*
X176000Y140500D03*
X172890Y153260D03*
X171700Y156900D03*
X169500Y180200D03*
X170800Y193100D03*
X172621Y208300D03*
X173800Y225400D03*
X170400Y214700D03*
X172400Y220700D03*
X175300Y240000D03*
X174400Y254736D03*
X179846Y255150D03*
X180458Y258825D03*
X174400Y251936D03*
X176900Y270100D03*
X174292Y263300D03*
X171592Y263312D03*
X168710Y272256D03*
X172977Y277000D03*
X182435Y281797D03*
X179217Y278528D03*
X168656Y275156D03*
X182232Y296424D03*
X174232Y304333D03*
X176563Y310917D03*
X176533Y314049D03*
X170550Y304050D03*
X169077Y308677D03*
X170561Y306631D03*
X181050Y332250D03*
X171098Y341224D03*
X182700Y342216D03*
X180600Y360200D03*
X177500Y369100D03*
X178850Y385634D03*
X182350D03*
X172530Y420950D03*
Y429470D03*
X184480Y429370D03*
X171400Y450600D03*
X193100Y69100D03*
X189400Y69600D03*
X184800Y100300D03*
X187700Y99000D03*
X187400Y101500D03*
X190800Y117200D03*
X193096Y115600D03*
X186891Y113991D03*
X190744Y114456D03*
X187069Y116800D03*
X184729Y115820D03*
X187435Y129623D03*
X195983Y132294D03*
X191482Y129294D03*
X195983D03*
X186200Y125600D03*
X184000Y140500D03*
X196577Y141185D03*
X189700Y140400D03*
X191693Y236370D03*
X196240Y253430D03*
X193084Y257400D03*
X194567Y255288D03*
X187400Y255700D03*
X190900Y271700D03*
X193386Y269142D03*
X184200Y264900D03*
X185000Y270700D03*
X195370Y273297D03*
X183625Y273500D03*
X196200Y278200D03*
X196100Y281820D03*
X187623Y297475D03*
X192380Y291900D03*
X196443Y294065D03*
X191199Y300200D03*
X192448Y308314D03*
X195031Y307182D03*
X194600Y313300D03*
X197853Y307200D03*
X197155Y314223D03*
X188546Y326356D03*
X190465Y344426D03*
X190600Y337900D03*
X183800Y345400D03*
X197775Y346617D03*
X194800Y341700D03*
X191408Y357451D03*
X197450Y356560D03*
X196050Y358770D03*
X191420Y354710D03*
X190965Y348090D03*
X197711Y349250D03*
X195000Y373900D03*
X187400Y379400D03*
X197400Y367600D03*
Y370250D03*
X197620Y385425D03*
X187300Y384300D03*
X197660Y390870D03*
X190050Y389140D03*
X190100Y392270D03*
X191843Y403995D03*
X189054Y397500D03*
X194500Y402600D03*
X195800Y396780D03*
X185245Y417500D03*
X190370Y422490D03*
X195000Y422540D03*
X199940Y423700D03*
X197600Y415400D03*
X190270Y409962D03*
X189762Y429177D03*
X195300Y432327D03*
X189766Y432050D03*
X189838Y434910D03*
X186720Y432490D03*
X186300Y448700D03*
X185000Y451500D03*
Y454000D03*
Y456500D03*
X191780Y453300D03*
Y456700D03*
X211400Y59238D03*
X204300Y60600D03*
X201500Y61000D03*
X209142Y53664D03*
X204100Y67400D03*
X201900Y83300D03*
X199940Y117500D03*
X211370Y117000D03*
X208200Y111760D03*
X199985Y132294D03*
X212757Y127064D03*
X212727Y129654D03*
X208627Y132394D03*
X208576Y128957D03*
X204120Y132294D03*
X200000Y128764D03*
X208500Y126057D03*
X212727Y132154D03*
X211490Y143700D03*
X205598Y140480D03*
X203542Y213254D03*
X206200Y255385D03*
X200680Y257540D03*
X206051Y247911D03*
X205500Y258300D03*
X201100Y265120D03*
X214034Y261482D03*
X201000Y262500D03*
X203090Y269229D03*
X205590Y269129D03*
X205900Y266130D03*
X204258Y286691D03*
X213258Y273265D03*
X204560Y301130D03*
X212911Y293869D03*
X206430Y298780D03*
X199729Y314565D03*
X198672Y318175D03*
X208628Y324665D03*
X200300Y328800D03*
X208000Y373240D03*
X208565Y404501D03*
X200222Y398150D03*
X213200Y399166D03*
X199880Y402846D03*
X207539Y408686D03*
X200000Y407040D03*
X205223Y422665D03*
X207278Y416022D03*
X206150Y412821D03*
X198600Y426600D03*
X202513Y434800D03*
X198405D03*
X199000Y444500D03*
X205200Y445400D03*
X213225Y442220D03*
X214306Y62233D03*
X229900Y61000D03*
X224000Y74275D03*
X218600Y92100D03*
X221300D03*
X224330Y83210D03*
X227760Y82524D03*
X219900Y101300D03*
X216400Y106400D03*
X226040Y101220D03*
X222890Y101240D03*
X215294Y117094D03*
X226887Y117297D03*
X223300Y117400D03*
X217262Y129294D03*
X225284Y132294D03*
X229342Y129240D03*
X221278Y129294D03*
X225284D03*
X217262Y132294D03*
X221278D03*
X225300Y125200D03*
X227700Y151900D03*
X221000Y243000D03*
X220100Y237200D03*
X223800Y254800D03*
X227316Y256700D03*
X215100Y244100D03*
X215500Y247111D03*
X216800Y255550D03*
X215510Y253310D03*
X225275Y246000D03*
X217500Y264000D03*
X230196Y267477D03*
X219900Y267100D03*
X220866Y272160D03*
X227232Y270539D03*
X226405Y266335D03*
X222833Y261668D03*
X219722Y286728D03*
X227841Y275773D03*
X219339Y284138D03*
X219359Y281580D03*
X226500Y273000D03*
X229220Y283250D03*
X223646Y293960D03*
X214400Y303997D03*
X216384Y312216D03*
X228800Y312100D03*
X226100Y325065D03*
X217300Y322800D03*
X225867Y345033D03*
X225650Y337520D03*
X221000Y343800D03*
X216405Y335970D03*
X214175Y333740D03*
X228230Y340040D03*
X221000Y352000D03*
X224632Y369825D03*
X225700Y362500D03*
X213490Y373690D03*
X226710Y364815D03*
X223420Y367080D03*
X220515Y384900D03*
X222575Y387625D03*
X227206Y400100D03*
X217390Y401340D03*
X222986Y400323D03*
X220134Y400780D03*
X219050Y418850D03*
X217725Y410150D03*
X221225D03*
X226830Y435170D03*
X225000Y433100D03*
X219250Y422150D03*
X213900Y436000D03*
X217100Y436100D03*
X224000Y449100D03*
X216725Y442220D03*
X237000Y47200D03*
X234537Y74638D03*
X240000Y67400D03*
X230600Y91700D03*
X239660Y91920D03*
X232150Y82480D03*
X235630Y104990D03*
X231592Y110500D03*
X240160Y107000D03*
X240710Y99570D03*
X232325Y101230D03*
X236648Y100739D03*
X238900Y114800D03*
X234500Y117500D03*
X230293Y117417D03*
X239900Y117550D03*
X239206Y112300D03*
X233511Y132594D03*
X234900Y126100D03*
X229396Y132294D03*
X233511Y129594D03*
X242500Y129000D03*
X242195Y141003D03*
X232384Y148884D03*
X230535Y244564D03*
X237700Y257387D03*
X237730Y248085D03*
X242690Y255300D03*
X230000Y255700D03*
X232300Y261200D03*
X239298Y268800D03*
X242940Y268500D03*
X233033Y266483D03*
X229630Y264404D03*
X242087Y271427D03*
X238531Y263081D03*
X231900Y272700D03*
X241188Y279347D03*
X241263Y282654D03*
X234500Y293500D03*
X242700Y306800D03*
X240500Y316575D03*
X236688Y311217D03*
X238400Y304200D03*
X228800Y305500D03*
X235400Y303800D03*
X242592Y330683D03*
X243010Y323400D03*
X230445Y325945D03*
X235000Y335300D03*
X231689Y334896D03*
X233500Y346911D03*
Y343911D03*
X231500Y352500D03*
X233650Y359628D03*
X233800Y354300D03*
X230287Y373100D03*
X232470Y382280D03*
X233600Y377300D03*
X233790Y384490D03*
X239750Y394970D03*
X236670Y394550D03*
X241231Y407285D03*
X236860Y407300D03*
X229900Y436600D03*
X236900Y440565D03*
X239500Y447750D03*
X235400Y451600D03*
X231250Y447000D03*
X235200Y449100D03*
X231400Y449500D03*
X241436Y445784D03*
X240200Y450650D03*
X236221Y454400D03*
X240010Y456000D03*
X240210Y453400D03*
X231400Y452000D03*
X252925Y54000D03*
X249475Y55812D03*
X256000Y56000D03*
X246200Y74600D03*
X253000Y77500D03*
X250000Y73000D03*
X255000Y82700D03*
X257800Y82800D03*
X256900Y87300D03*
X251200Y93800D03*
X251900Y100100D03*
X255213Y106099D03*
X249988Y105792D03*
X246488D03*
X244208Y97302D03*
X247200Y117400D03*
X253100Y119900D03*
X245310Y113910D03*
X245500Y127800D03*
X245520Y130600D03*
X258500Y146400D03*
X251354Y152877D03*
X249300Y237600D03*
X247689Y247929D03*
X253110Y254909D03*
X253100Y257800D03*
X252639Y247885D03*
X256700Y263800D03*
X255700Y260000D03*
X247470Y269990D03*
X250288Y273581D03*
X251459Y286542D03*
Y283542D03*
X257145Y279700D03*
X246514Y294325D03*
Y296825D03*
X258100Y295080D03*
X254355Y300577D03*
X247923Y316400D03*
X245900Y305000D03*
X257900Y312100D03*
X248900Y304900D03*
X247923Y319000D03*
X253320Y323327D03*
X256124Y336355D03*
X243750Y369730D03*
X243700Y372730D03*
X244790Y375910D03*
X248800Y385700D03*
X249400Y410300D03*
X252350Y412850D03*
X257810Y435100D03*
X246700Y451500D03*
X246500Y448500D03*
X243375Y448375D03*
X246700Y454100D03*
X259000Y47500D03*
X267939Y41122D03*
X268500Y45500D03*
X259894Y90072D03*
X263102Y91725D03*
X272505Y83545D03*
X260050Y87026D03*
X265801Y106040D03*
X260970Y98600D03*
X258713Y106099D03*
X264989Y101732D03*
X271602Y121400D03*
X269561Y130987D03*
X271300Y132900D03*
X269493Y138604D03*
X260200Y132395D03*
X260388Y125001D03*
X268442Y153299D03*
X265942D03*
Y150799D03*
X268442D03*
X269004Y144450D03*
Y141950D03*
X269133Y164982D03*
X265226D03*
X268339Y222126D03*
X272300Y251000D03*
X258628Y247600D03*
X258475Y254872D03*
X267100Y265000D03*
X269016Y266991D03*
X259500Y263700D03*
X262730Y267600D03*
X258000Y266300D03*
X266600Y268700D03*
X262700Y265100D03*
X258000Y284900D03*
X262100Y280700D03*
X266250Y297900D03*
X266200Y294800D03*
X261500Y290440D03*
X266300Y307500D03*
X262310Y311225D03*
X264265Y315817D03*
X261300Y334100D03*
X271100Y346575D03*
X259420Y343230D03*
Y340630D03*
X273580Y354250D03*
X271990Y362360D03*
X265320Y392290D03*
X274190Y408900D03*
X265100Y395100D03*
X272400Y392400D03*
X269700Y411379D03*
X271500Y418300D03*
X267100Y432900D03*
X263800Y430300D03*
X272999Y430500D03*
X271710Y449840D03*
X266727Y443185D03*
X261700Y439700D03*
X265130Y440070D03*
X261100Y443500D03*
X269561Y456044D03*
X286000Y47000D03*
X277000Y51665D03*
X274500Y58000D03*
X279934Y51688D03*
X279800Y72700D03*
X290000Y82000D03*
X273400Y92800D03*
X276400Y92300D03*
X287578Y84092D03*
X283500Y89500D03*
X277505Y83545D03*
X282505D03*
X278300Y95019D03*
X274760Y105140D03*
X275386Y102710D03*
X280910Y102880D03*
X288116Y120306D03*
X285250Y117250D03*
X274200Y109500D03*
X280400Y126000D03*
X283500D03*
X275960Y126010D03*
X273450Y125050D03*
X287796Y131542D03*
X288280Y126212D03*
X280616Y150971D03*
X283616D03*
X287555Y142419D03*
X285899Y153542D03*
X283399D03*
X279457Y171318D03*
X279983Y235254D03*
X282483D03*
X283974Y251372D03*
X286800Y251400D03*
X276200Y251500D03*
X280082Y251328D03*
X280030Y267098D03*
Y264098D03*
X284357Y267027D03*
Y264027D03*
X285911Y269899D03*
X281889D03*
X287755Y287538D03*
X282911Y279569D03*
X285911D03*
X287507Y301596D03*
X281300Y308800D03*
X287050Y305850D03*
X289939Y309060D03*
X276660Y316900D03*
X273355Y330001D03*
X286372Y320700D03*
X289600Y322253D03*
X286372Y326768D03*
X285860Y336131D03*
X277500Y348469D03*
X275520Y357910D03*
X277290Y355820D03*
X277572Y351198D03*
X287761Y366200D03*
X287500Y376900D03*
X276145Y366455D03*
X276400Y370400D03*
X283664Y379236D03*
X273100Y381500D03*
X283973Y382553D03*
X285191Y390840D03*
X287630Y389378D03*
X275700Y403500D03*
X277700Y406100D03*
X287476Y396680D03*
X278900Y421400D03*
X281300Y416200D03*
X277700Y412580D03*
X287500Y416100D03*
X278409Y433722D03*
X276400Y431810D03*
X275100Y427682D03*
X274619Y424725D03*
X283622Y447155D03*
X275138Y451215D03*
X276632Y439502D03*
X283674Y449975D03*
X283715Y452769D03*
X297466Y51521D03*
X300425Y54516D03*
X290000Y67975D03*
X297575Y73738D03*
X293773Y73530D03*
X300070Y84000D03*
X294600Y106900D03*
X298575Y101900D03*
X304000Y116500D03*
X294800Y111800D03*
X298975Y118900D03*
X301000Y121016D03*
X300500Y125000D03*
X295075Y119100D03*
X301000Y129900D03*
X290200Y129500D03*
X298005Y151118D03*
Y148618D03*
Y146118D03*
X292204Y142610D03*
X301936Y143897D03*
X296734Y216079D03*
X290586Y234844D03*
X288086D03*
X301120Y235626D03*
Y238765D03*
X299138Y244513D03*
X291500Y287670D03*
Y285170D03*
X298840Y279640D03*
X291000Y297700D03*
X291300Y315900D03*
X290120Y339370D03*
X290000Y335600D03*
X300700Y341300D03*
X295500Y354920D03*
X296780Y371500D03*
X298152Y393332D03*
X292700Y403700D03*
X291623Y447747D03*
X291703Y450819D03*
X295729Y453912D03*
Y456912D03*
Y459912D03*
X297738Y452418D03*
Y458418D03*
Y455418D03*
X316025Y60200D03*
X309570Y84000D03*
X316066Y108407D03*
X315100Y116400D03*
X307400Y122300D03*
X315900Y125900D03*
X313800Y124300D03*
X307560Y128500D03*
X305936Y143897D03*
X309936D03*
X313936D03*
X307487Y219503D03*
X304987D03*
X310449Y218617D03*
X317110Y219140D03*
X309521Y235352D03*
Y238741D03*
X305000Y252400D03*
X307600Y252300D03*
X307800Y259200D03*
X312272Y282107D03*
X302800Y286200D03*
X311670Y285160D03*
X302879Y282487D03*
Y279686D03*
X309700Y294789D03*
X306500Y301500D03*
X303000Y309200D03*
X306200Y308800D03*
X312300Y340700D03*
X308906Y362637D03*
X314340Y373296D03*
X311925Y366475D03*
X308926Y401900D03*
X321800Y60055D03*
X322500Y102900D03*
X320500Y100400D03*
X324011Y118843D03*
X324023Y121943D03*
Y115643D03*
X320765Y114582D03*
X320938Y122677D03*
X318000Y117200D03*
X331741Y138243D03*
Y125796D03*
X317936Y143897D03*
X323509Y153377D03*
X329005Y152657D03*
X328087Y141608D03*
X331641Y141743D03*
X321600Y142100D03*
X331405Y164911D03*
Y159911D03*
Y154911D03*
Y167411D03*
Y179911D03*
Y174911D03*
Y169911D03*
Y182926D03*
Y172411D03*
Y189911D03*
X320054Y195163D03*
X326932Y205685D03*
X326733Y209885D03*
X321045Y210257D03*
X320937Y212839D03*
X326733Y201485D03*
X320054Y198663D03*
X326731Y213648D03*
X320931Y215387D03*
X317922Y238717D03*
Y235328D03*
X326323Y235304D03*
Y238693D03*
X327162Y278972D03*
X325007Y328608D03*
Y326008D03*
X327704Y328635D03*
Y326035D03*
X325007Y323508D03*
X327704Y323535D03*
X329925Y356016D03*
X325900Y365643D03*
X326100Y375717D03*
X326200Y370681D03*
X331500Y383300D03*
X326375Y380724D03*
X325593Y406500D03*
X329093D03*
X318593D03*
X322093D03*
X339900Y69100D03*
Y66000D03*
X339908Y104577D03*
Y108593D03*
X342200Y100500D03*
X342180Y106900D03*
X339908Y112609D03*
X339369Y151952D03*
X339939Y162911D03*
X339812Y173380D03*
X339800Y182926D03*
X337400Y193449D03*
X334724Y238669D03*
Y235280D03*
X337467Y236984D03*
X336461Y283202D03*
X340612Y278972D03*
X339700Y293000D03*
X347100Y313700D03*
X345500Y342690D03*
X335475Y358500D03*
Y367500D03*
X335708Y372008D03*
X335500Y380000D03*
X375904Y-438145D03*
X375964Y-215959D03*
X375876Y-159873D03*
X375964Y12313D03*
X375904Y68399D03*
X375964Y381585D03*
X379304Y-438145D03*
X379364Y-215959D03*
X379276Y-159873D03*
X379364Y12313D03*
X379304Y68399D03*
X379364Y381585D03*
X396992Y-464207D03*
X400392D03*
X397080Y-121021D03*
X400480D03*
G54D23*
X23819Y339154D03*
Y359154D03*
Y369154D03*
Y379154D03*
Y389154D03*
Y399154D03*
Y409154D03*
X65709Y42244D03*
Y52244D03*
X75709Y42244D03*
Y52244D03*
X95709Y42244D03*
X85709D03*
Y52244D03*
G54D25*
X63898Y24764D03*
X73898D03*
X90472D03*
X100472D03*
X117047D03*
X127047D03*
X211142D03*
X237717D03*
X247717D03*
G54D28*
X62458Y346425D03*
Y343275D03*
Y355873D03*
X58564Y354280D03*
X65607Y352724D03*
Y359023D03*
Y371584D03*
X75056Y346425D03*
X68757D03*
X81355D03*
X78206Y349574D03*
X71906D03*
X68757D03*
X78206Y359023D03*
X75056Y352724D03*
Y349574D03*
X78206Y355873D03*
X65607D03*
X68757Y362173D03*
Y359023D03*
X71906D03*
X75056Y355873D03*
X71906Y352724D03*
X68757Y355873D03*
X78206Y374733D03*
Y362173D03*
X75056D03*
X71906Y371584D03*
X75056Y365322D03*
X71906D03*
X68757D03*
Y371584D03*
X75056Y374733D03*
X71906D03*
X68757D03*
X65607D03*
X71906Y362173D03*
X78206Y365322D03*
Y371584D03*
X68757Y377883D03*
X78206Y381033D03*
X65607D03*
X71906Y377883D03*
X65607Y384182D03*
X68719Y381033D03*
X78206Y377883D03*
X71906Y387332D03*
X71869Y381033D03*
X71906Y384182D03*
X87617Y352724D03*
X90766Y349574D03*
X93916Y352724D03*
X81355Y355873D03*
X90766Y352724D03*
X87617Y349574D03*
X90766Y355873D03*
X87617D03*
X90766Y359023D03*
X81355Y349574D03*
X87617Y359023D03*
X90766Y374733D03*
Y362173D03*
X81355D03*
X87617D03*
X81355Y374733D03*
X87617D03*
X90766Y371584D03*
Y365322D03*
X81355Y377883D03*
Y387332D03*
Y384182D03*
X87617D03*
X90766Y377883D03*
X87617Y390481D03*
X81355Y381033D03*
X87617Y387332D03*
X90766Y381033D03*
X87617Y377883D03*
X90766Y390481D03*
Y387332D03*
Y384182D03*
X92360Y394175D03*
X89210D03*
X103365Y346425D03*
X106564Y346400D03*
X100253Y346387D03*
X93916Y349574D03*
X97066D03*
X106515Y352724D03*
X106514Y349574D03*
X97066Y352724D03*
X100215Y355873D03*
X93916D03*
X100215Y349574D03*
Y387332D03*
X97066D03*
X93916Y384182D03*
X97066D03*
X100215Y381033D03*
X93916D03*
Y387332D03*
X166300Y212300D03*
X181495Y153449D03*
X175196Y159748D03*
X178346Y156599D03*
X181495Y159748D03*
X175196Y156599D03*
X181495D03*
Y166047D03*
X184645D03*
X181495Y162898D03*
X178346Y159748D03*
X181495Y178646D03*
Y175496D03*
X184645Y181795D03*
X181495D03*
Y172347D03*
X184645Y175496D03*
X174569Y180202D03*
X178346Y175496D03*
X175196Y172347D03*
X173000Y170200D03*
X181495Y169197D03*
Y184945D03*
Y197506D03*
X178346D03*
Y191244D03*
X181495D03*
X175196Y197506D03*
X174336Y192800D03*
X181495Y188095D03*
X178346D03*
X175196Y200655D03*
X178346Y210104D03*
X181495Y203805D03*
Y206955D03*
X175196Y210104D03*
X178346Y206955D03*
X175196D03*
Y203805D03*
X178346D03*
X171836Y200655D03*
Y198300D03*
X181495Y200655D03*
Y219553D03*
X175196Y213254D03*
X184645Y219553D03*
X178346Y229002D03*
X181495Y225852D03*
Y222703D03*
X184645Y229002D03*
X174600Y217800D03*
X181495Y216403D03*
X175196Y229002D03*
X181495D03*
X187794Y153449D03*
X192400Y152804D03*
X184645Y153449D03*
X197243Y166047D03*
X194094Y162898D03*
X197243Y159748D03*
X194094D03*
X197243Y162898D03*
X184645Y156599D03*
X187794Y162898D03*
Y166047D03*
X184645Y162898D03*
Y159748D03*
X190944Y162898D03*
Y159748D03*
X194094Y166047D03*
X190944D03*
X200393Y162898D03*
X187794Y156599D03*
Y178646D03*
X194094Y169197D03*
X190944Y172347D03*
Y175496D03*
X197243D03*
X190944Y178646D03*
Y181795D03*
X187794Y175496D03*
X184645Y178646D03*
X190944Y169197D03*
X187794Y172347D03*
X184645Y169197D03*
Y172347D03*
X187794Y169197D03*
X197243Y184945D03*
X190944Y197506D03*
Y184945D03*
Y188095D03*
Y191244D03*
X187794Y197506D03*
Y184945D03*
X184645Y197506D03*
Y184945D03*
Y191244D03*
Y188095D03*
X190944Y200655D03*
Y210104D03*
Y203805D03*
X187794Y200655D03*
X184645Y210104D03*
Y200655D03*
Y203805D03*
X187794Y210104D03*
X190944Y219553D03*
X194094Y222703D03*
X200393Y229002D03*
X194094Y225852D03*
X187794D03*
Y219553D03*
X190944Y213254D03*
Y222702D03*
X200393Y222703D03*
X197243Y225852D03*
Y222703D03*
X184645Y225852D03*
X187794Y222703D03*
X184645D03*
Y213254D03*
X194094Y219553D03*
X187794Y229002D03*
X197243Y235301D03*
X194094Y229002D03*
X197243D03*
Y232151D03*
X209842Y153449D03*
Y159748D03*
X206692Y156599D03*
X203542Y166047D03*
X206692Y162898D03*
X203542D03*
X200393Y159748D03*
X209842Y166047D03*
Y162898D03*
X212991D03*
X203542Y159748D03*
X200393Y166047D03*
X206692D03*
X212991D03*
X206692Y159748D03*
X209842Y169197D03*
X206692Y181795D03*
X203542Y175496D03*
X206692D03*
X209842D03*
X200393D03*
X212991Y184945D03*
Y197506D03*
X203542Y206955D03*
X212991Y203805D03*
X206692Y206955D03*
X209842D03*
X200393D03*
X212991Y200655D03*
Y213254D03*
X200393D03*
Y219553D03*
X212991Y222740D03*
X209842Y213254D03*
Y225852D03*
X203542Y222703D03*
X200393Y225852D03*
X206692Y219553D03*
X203542Y225852D03*
X206692Y229002D03*
X212991D03*
X203542Y219553D03*
X206692Y222703D03*
X209842D03*
X212991Y225890D03*
X206692Y225852D03*
X203542Y229002D03*
X209746Y235397D03*
X203542Y235301D03*
X209842Y232151D03*
X200393D03*
X206692D03*
X212991D03*
X209842Y229002D03*
X225658Y153369D03*
X225552Y159748D03*
X222402Y162898D03*
X219253Y166047D03*
X225552Y162898D03*
Y166047D03*
X222402D03*
X219253Y159748D03*
X222402D03*
X219253Y162898D03*
Y156599D03*
X222402D03*
Y178646D03*
X225552Y181795D03*
X214547Y174852D03*
X225552Y169197D03*
X219253D03*
X225552Y191244D03*
Y188095D03*
X222402Y191244D03*
X219253Y197506D03*
X222402D03*
X219253Y188095D03*
Y200655D03*
Y206955D03*
Y210104D03*
Y203805D03*
Y213254D03*
X228739Y222703D03*
X216141D03*
X228702Y229002D03*
X225590Y222720D03*
X216103Y219591D03*
X219253Y219553D03*
X225590Y225852D03*
X222440Y222703D03*
X225552Y219553D03*
X222402D03*
Y229002D03*
X222440Y225852D03*
X219290D03*
Y222703D03*
X225552Y229002D03*
X219253D03*
X235001Y153449D03*
X228702Y162898D03*
X238150D03*
X231851Y166047D03*
X238150D03*
X228702Y159748D03*
Y166047D03*
X238150Y156599D03*
X235001D03*
X231851D03*
Y162898D03*
Y159748D03*
X235001Y162898D03*
Y159748D03*
X238150D03*
X241300D03*
X231851Y169197D03*
Y178646D03*
X235001Y169197D03*
X241300Y175496D03*
Y178646D03*
Y172347D03*
X235001Y178646D03*
Y175496D03*
X228702Y181795D03*
Y178646D03*
X235001Y188095D03*
Y191244D03*
Y197506D03*
X241300Y184945D03*
Y197506D03*
Y188095D03*
X244450Y200655D03*
X228702D03*
X235001Y203805D03*
X231851D03*
X228702D03*
X241300Y200655D03*
Y210104D03*
X235001D03*
X231851D03*
X228702D03*
X235038Y225890D03*
X228739Y225852D03*
X238150Y222703D03*
X231889Y219591D03*
Y222740D03*
X235038D03*
X231889Y225890D03*
X228739Y216441D03*
X241338Y225890D03*
X231851Y229002D03*
X241300D03*
X239870Y237596D03*
X242870D03*
X235038Y229039D03*
X250749Y169197D03*
X247637Y162898D03*
X247599Y166047D03*
X253898Y169197D03*
X257048Y172347D03*
X250749Y181795D03*
X244450D03*
X250749Y175496D03*
Y178646D03*
X247599Y172347D03*
X244450Y175496D03*
X250749Y172347D03*
X247599Y178646D03*
X253898Y175496D03*
X244450Y178646D03*
Y172347D03*
X250749Y184945D03*
X244450Y169197D03*
Y197506D03*
X247599Y191244D03*
X257048Y197506D03*
X253898D03*
X250749D03*
X247599Y184945D03*
X244450Y188095D03*
X257048Y191244D03*
X250749Y188095D03*
X244450Y184945D03*
X250749Y191244D03*
X244450D03*
X250749Y203805D03*
X247599Y206955D03*
Y210104D03*
X250749Y206955D03*
X247599Y200655D03*
X257048Y206955D03*
X250749Y200655D03*
X257048D03*
X250749Y210104D03*
X244450Y203805D03*
X250749Y222703D03*
Y225852D03*
X253898Y219553D03*
Y222703D03*
X257048Y213254D03*
X250749D03*
X247599D03*
X253898D03*
X247637Y225852D03*
X244450Y232151D03*
X247599D03*
X253898D03*
X257048D03*
X250749Y229002D03*
X253898D03*
X250749Y235301D03*
X253898D03*
X267722Y176791D03*
X264222D03*
X271209Y177524D03*
X270472Y188488D03*
X264118Y188095D03*
X266080Y207262D03*
X262580D03*
X263580Y214593D03*
X267080D03*
X285482Y168102D03*
X273644Y174267D03*
X282975Y172975D03*
X286105Y176085D03*
X289254Y194839D03*
X286105Y185534D03*
Y194839D03*
Y204288D03*
X286106Y210587D03*
X286105Y213721D03*
X289110Y163487D03*
X292260D03*
X295410Y169786D03*
X292404Y176085D03*
X295410Y172936D03*
X289254Y172792D03*
X292260Y169643D03*
X295410Y179235D03*
X292384Y172936D03*
X289254Y176085D03*
Y182385D03*
X292260Y179235D03*
X289111D03*
X292404Y191690D03*
X289254D03*
X292404Y185534D03*
Y194983D03*
X295410Y194839D03*
X295411Y185534D03*
X289254D03*
Y197989D03*
X298714Y210477D03*
X292404Y210587D03*
Y201282D03*
X299667Y201334D03*
X292404Y213737D03*
X289254Y201139D03*
X295410Y210587D03*
X311158Y163487D03*
X308008Y166637D03*
X314307Y163487D03*
X314930Y168140D03*
Y171289D03*
Y177588D03*
X305002Y176085D03*
Y169786D03*
Y172936D03*
X308152Y169786D03*
X311158Y169643D03*
X308152Y172936D03*
Y176085D03*
Y182385D03*
X305002Y179235D03*
X308152D03*
X314930Y180738D03*
Y174439D03*
X308008Y191690D03*
X311158D03*
X308008Y188540D03*
Y185391D03*
Y198133D03*
X314307Y185534D03*
X311158Y188540D03*
X308008Y194839D03*
X311158Y197989D03*
X314307Y194839D03*
Y197989D03*
X308008Y207438D03*
X308152Y204432D03*
X305002D03*
X311158Y210587D03*
X308008Y210731D03*
X305002Y210587D03*
X314307Y201139D03*
Y204288D03*
Y210587D03*
Y213737D03*
G54D39*
X372604Y-455313D03*
Y-430313D03*
X372664Y-223791D03*
Y-198791D03*
X372576Y-177041D03*
Y-152041D03*
X372664Y4481D03*
Y29481D03*
X372604Y51231D03*
Y76231D03*
X372664Y373753D03*
Y398753D03*
X393692Y-481375D03*
X382604Y-455313D03*
X393692Y-456375D03*
X382604Y-430313D03*
X382664Y-223791D03*
Y-198791D03*
X382576Y-177041D03*
Y-152041D03*
X393780Y-128853D03*
Y-103853D03*
X393750Y-82222D03*
Y-57222D03*
X382664Y4481D03*
Y29481D03*
X382604Y51231D03*
Y76231D03*
X393750Y200538D03*
Y225538D03*
Y247050D03*
Y272050D03*
X382664Y373753D03*
X393750Y398810D03*
X382664Y398753D03*
X393750Y423810D03*
X403692Y-481375D03*
Y-456375D03*
X403780Y-128853D03*
Y-103853D03*
X403750Y-82222D03*
D03*
Y-57222D03*
D03*
Y200538D03*
D03*
Y225538D03*
D03*
Y247050D03*
D03*
Y272050D03*
D03*
Y398810D03*
D03*
Y423810D03*
D03*
X413750Y-82222D03*
Y-57222D03*
Y200538D03*
Y225538D03*
Y247050D03*
Y272050D03*
Y398810D03*
Y423810D03*
G54D14*
X3000Y8494D03*
Y28494D03*
Y48494D03*
Y68494D03*
Y88494D03*
Y108494D03*
Y128494D03*
Y148494D03*
Y168494D03*
Y188494D03*
Y208494D03*
Y228494D03*
Y248494D03*
Y268494D03*
Y288494D03*
Y308494D03*
Y342126D03*
Y362126D03*
Y382126D03*
Y402126D03*
Y422126D03*
Y442126D03*
X16626Y195848D03*
X19129D03*
Y193048D03*
X16626D03*
X19129Y204248D03*
X17000Y208017D03*
X16626Y198648D03*
Y201448D03*
X19129Y198648D03*
Y201448D03*
X16626Y204248D03*
X6200Y312900D03*
X13827Y325310D03*
X21250Y206220D03*
X36599Y189016D03*
X37360Y194050D03*
X37823Y198346D03*
X48035Y191535D03*
X47714Y212227D03*
X48940Y204871D03*
X52155Y121218D03*
X60112Y113992D03*
X222402Y169197D03*
X238188Y225852D03*
X228739Y213254D03*
X250749Y159748D03*
X244020Y235518D03*
X244487Y229002D03*
X268510Y179088D03*
X301120Y226421D03*
Y229810D03*
X302687Y275497D03*
X296938Y325700D03*
X311301Y182385D03*
X309521Y226397D03*
Y229786D03*
X314969Y456527D03*
X329297Y134594D03*
Y129890D03*
X321276Y134532D03*
X321349Y130044D03*
X326323Y226349D03*
X317922Y226373D03*
X326323Y229738D03*
X317922Y229762D03*
X373480Y-210223D03*
X370965D03*
Y-206970D03*
X376406Y-206985D03*
X373480Y-206970D03*
X372271Y-213263D03*
X373480Y18049D03*
X370965D03*
X372271Y15009D03*
X370965Y21302D03*
X376406Y21287D03*
X373480Y21302D03*
X372271Y384281D03*
X376406Y390559D03*
X373480Y387321D03*
Y390574D03*
X370965Y387321D03*
Y390574D03*
X383057Y-213263D03*
X381848Y-206970D03*
X384363D03*
Y-210223D03*
X381848D03*
X378922Y-206970D03*
X392081Y-115285D03*
Y-112032D03*
X383057Y15009D03*
X384363Y18049D03*
X381848D03*
Y21302D03*
X384363D03*
X378922D03*
X391950Y214106D03*
Y217359D03*
X378922Y390574D03*
X381848D03*
Y387321D03*
X384363Y390574D03*
Y387321D03*
X383057Y384281D03*
X391950Y412378D03*
Y415631D03*
X394596Y-115285D03*
X393387Y-118325D03*
X404173D03*
X405479Y-115285D03*
X402964D03*
X397522Y-112047D03*
X394596Y-112032D03*
X402964D03*
X405479D03*
X400038D03*
X393357Y211066D03*
X403857D03*
X394450Y217359D03*
Y214106D03*
X396950Y217359D03*
X399450Y217344D03*
X402450Y217359D03*
X404950D03*
X402450Y214106D03*
X404950D03*
X394450Y415631D03*
Y412378D03*
X396950Y415631D03*
X399450Y415616D03*
X393357Y409338D03*
X402450Y415631D03*
X404950D03*
X402450Y412378D03*
X404950D03*
X403857Y409338D03*
X414143Y211066D03*
X415550Y214106D03*
Y217359D03*
X413050D03*
Y214106D03*
X410550Y217359D03*
X408050Y217344D03*
X415550Y412378D03*
Y415631D03*
X413050D03*
Y412378D03*
X410550Y415631D03*
X408050Y415616D03*
X414143Y409338D03*
G54D22*
X23723Y123791D03*
Y120791D03*
X32223Y123791D03*
Y120791D03*
X40723Y123791D03*
Y120791D03*
X49223Y123791D03*
Y121291D03*
X38300Y109200D03*
X60411Y130200D03*
X57470Y426544D03*
X51535D03*
X56482Y450344D03*
X62600Y450700D03*
X71035Y426543D03*
X76770D03*
X142780Y266830D03*
X142500Y345800D03*
X175359Y153286D03*
X178346Y162898D03*
Y172347D03*
Y184945D03*
X181194Y294074D03*
X169669Y399419D03*
X197243Y156599D03*
X187794Y159748D03*
X197243Y178646D03*
X187794Y181795D03*
X197243Y191244D03*
Y197506D03*
Y203805D03*
X184645Y206955D03*
X197243Y200655D03*
Y219553D03*
X194094Y232151D03*
X184645D03*
X185725Y307320D03*
X209842Y156599D03*
X203542Y169197D03*
X212991D03*
X206692D03*
X212991Y181795D03*
X206692Y178646D03*
X209842Y181795D03*
X203542Y191244D03*
X206692D03*
X209842Y184945D03*
X200393Y191244D03*
X203542Y197506D03*
X209842D03*
X203542Y210104D03*
X212991Y206955D03*
Y210104D03*
X209842D03*
X200393D03*
X203542Y200655D03*
X209842D03*
X212991Y219553D03*
X205130Y282000D03*
X204207Y278200D03*
X225552Y156599D03*
X219253Y178646D03*
X225552D03*
Y184945D03*
X219253Y232151D03*
X215600Y316800D03*
X228702Y169197D03*
X231851Y191244D03*
X241300D03*
X235001Y184945D03*
X228702Y191244D03*
X235001Y200655D03*
Y206955D03*
Y219553D03*
X241300Y213254D03*
X238150Y219553D03*
X228702D03*
X238630Y235654D03*
X231851Y232151D03*
X241300D03*
X255492Y152905D03*
X244450Y156599D03*
X253898Y172347D03*
Y178646D03*
X247599Y181795D03*
Y175496D03*
X253898Y191244D03*
Y184945D03*
X247599Y197506D03*
Y188095D03*
Y203805D03*
X253898Y206955D03*
Y200655D03*
X257048Y219553D03*
X250749D03*
Y232151D03*
X257048Y235301D03*
X263294Y153366D03*
X263030Y150846D03*
X268391Y207262D03*
X269391Y214593D03*
X280744Y142070D03*
X283248Y142046D03*
X287725Y363473D03*
X293693Y152232D03*
X290889Y152318D03*
X297372Y196616D03*
X308500Y382100D03*
X339800Y154911D03*
Y159911D03*
Y165911D03*
Y169911D03*
Y176911D03*
Y179911D03*
Y185911D03*
Y189911D03*
X337004Y202113D03*
Y206113D03*
Y210113D03*
G54D37*
X262880Y178977D03*
X308460Y214178D03*
G54D41*
X441000Y-454000D03*
X451000D03*
X441000Y-333400D03*
X451000D03*
X441000Y2000D03*
X451000D03*
X441000Y116000D03*
X451000D03*
G54D15*
X17716Y18465D03*
X45276D03*
X264173Y20040D03*
X291733D03*
X309055Y18465D03*
X336615D03*
G54D31*
X143118Y44803D03*
X194851D03*
G54D32*
X153237Y58583D03*
X165048Y52677D03*
X155205D03*
X161111Y58583D03*
X168985D03*
X172922Y52677D03*
X176859Y58583D03*
X184733D03*
G54D40*
X441000Y-444000D03*
X451000D03*
Y-355000D03*
X441000D03*
Y-323400D03*
X451000D03*
Y-245000D03*
X441000D03*
X451000Y-215000D03*
X441000D03*
Y-136600D03*
X451000D03*
Y-107000D03*
X441000D03*
Y-18000D03*
X451000D03*
X441000Y12000D03*
X451000D03*
Y96000D03*
X441000D03*
Y126000D03*
X451000D03*
Y200000D03*
X441000D03*
X451000Y230000D03*
X441000D03*
Y304000D03*
X451000D03*
Y336000D03*
X441000D03*
Y420000D03*
X451000D03*
G54D44*
X441000Y-126600D03*
X451000D03*
X441000Y-8000D03*
X451000D03*
X441000Y314000D03*
X451000D03*
X441000Y430000D03*
X451000D03*
G54D18*
X24016Y89331D03*
X330315D03*
G54D11*
X-61709Y56192D03*
X-51709D03*
X-61100Y250316D03*
X-61000Y382816D03*
X-51100Y250316D03*
X-51000Y382816D03*
X-35000Y56184D03*
X-25000D03*
X-25100Y250316D03*
X-35100D03*
X-36000Y418816D03*
X-26000D03*
G54D26*
X65945Y297776D03*
G54D36*
X236220Y424016D03*
X301181D03*
G54D33*
X144685Y297776D03*
G54D17*
X22047Y46417D03*
X333466D03*
G54D30*
X105316Y213343D03*
G54D24*
X23819Y349154D03*
X95709Y52244D03*
G54D34*
X182764Y52677D03*
G54D35*
X221142Y24764D03*
G54D10*
X-56709Y43008D03*
X-30000Y43000D03*
G54D29*
X105315Y186571D03*
G54D21*
X27300Y68200D03*
X340639Y432809D03*
G54D20*
X18000Y240900D03*
Y237900D03*
Y249900D03*
Y246900D03*
Y243900D03*
X15688Y259063D03*
X21135Y236587D03*
X21205Y232767D03*
X21135Y240667D03*
Y243737D03*
X24690Y246467D03*
Y251967D03*
X21135Y246837D03*
X21035Y249937D03*
X24690Y249267D03*
X22237Y311481D03*
Y308592D03*
X30638Y311957D03*
Y309068D03*
X22692Y466518D03*
X47440Y308691D03*
X39039Y309044D03*
Y311933D03*
X47440Y312080D03*
X63300Y237600D03*
X68375Y144100D03*
X70580Y167179D03*
X65800Y260875D03*
X81600Y241500D03*
X87500Y237300D03*
X84000Y261375D03*
X103500Y240619D03*
X113590Y245170D03*
X143300Y396400D03*
X146600Y410600D03*
X172550Y398690D03*
X200274Y410960D03*
X225552Y197543D03*
X225441Y282267D03*
X257048Y225890D03*
X292361Y197970D03*
X314985Y397639D03*
Y394639D03*
X332470Y397092D03*
Y394092D03*
X331646Y466536D03*
X339101Y117328D03*
Y121128D03*
X337842Y128533D03*
X334723Y226349D03*
Y229738D03*
X351331Y20788D03*
Y40788D03*
Y60788D03*
Y80788D03*
Y100788D03*
Y120788D03*
Y140788D03*
Y160788D03*
Y180788D03*
Y200788D03*
Y220788D03*
Y240788D03*
Y260788D03*
Y280788D03*
Y300788D03*
Y357531D03*
Y377531D03*
Y397531D03*
Y417531D03*
Y437531D03*
X373420Y-447134D03*
X370905D03*
Y-443881D03*
X373420D03*
X376346Y-447134D03*
X372211Y-440841D03*
X372183Y-162569D03*
X373392Y-168862D03*
X370877D03*
Y-165609D03*
X373392D03*
X376318Y-168862D03*
X373420Y59410D03*
X370905D03*
Y62663D03*
X373420D03*
X376346Y59410D03*
X372211Y65703D03*
X391993Y-473196D03*
Y-469943D03*
X381788Y-443881D03*
X384303D03*
Y-447134D03*
X378862Y-447119D03*
X381788Y-447134D03*
X382997Y-440841D03*
X381760Y-165609D03*
X384275D03*
Y-168862D03*
X378834Y-168847D03*
X381760Y-168862D03*
X382969Y-162569D03*
X391950Y-74043D03*
Y-70790D03*
X381788Y62663D03*
X384303D03*
Y59410D03*
X378862Y59425D03*
X381788Y59410D03*
X382997Y65703D03*
X391950Y255229D03*
Y258482D03*
X405391Y-473196D03*
X399950Y-473181D03*
X402876Y-473196D03*
X394508D03*
X397434D03*
X402876Y-469943D03*
X405391D03*
X404085Y-466903D03*
X393299D03*
X394508Y-469943D03*
X399450Y-74028D03*
X394450Y-74043D03*
Y-70790D03*
X396950Y-74043D03*
X405050D03*
X402550D03*
X405050Y-70790D03*
X402550D03*
X393357Y-67750D03*
X403643D03*
X394450Y255229D03*
X396950D03*
X399450Y255244D03*
X405050Y255229D03*
X402550D03*
X394450Y258482D03*
X393357Y261522D03*
X405050Y258482D03*
X402550D03*
X403643Y261522D03*
X415550Y-70790D03*
Y-74043D03*
X413050D03*
Y-70790D03*
X410550Y-74043D03*
X408050Y-74028D03*
X414143Y-67750D03*
X415550Y255229D03*
X413050D03*
X410550D03*
X408050Y255244D03*
X415550Y258482D03*
X413050D03*
X414143Y261522D03*
G54D38*
X285482Y190187D03*
G54D16*
X9407Y10554D03*
X12900Y105500D03*
X17000Y211541D03*
Y215713D03*
Y219288D03*
X8300Y314700D03*
X22218Y3000D03*
X27323Y25842D03*
X31920Y186610D03*
X25811Y319400D03*
X32000Y326300D03*
X23535Y329990D03*
X34300Y375000D03*
X33100Y392100D03*
X20225Y447671D03*
X42218Y3000D03*
X35044Y35751D03*
X43926Y62248D03*
X45276Y98488D03*
X47294Y184491D03*
X39567Y243133D03*
X40500Y236900D03*
X41574Y255937D03*
X44500Y355500D03*
X38200Y364855D03*
X36600Y408600D03*
X40848Y448440D03*
X62218Y3000D03*
X53000Y41500D03*
X59425Y53075D03*
X50508Y57459D03*
X57500Y75500D03*
X60000D03*
X53267Y109094D03*
X57141Y209341D03*
X59900Y199900D03*
X52000Y230400D03*
X62500Y272500D03*
X60561Y314843D03*
X62458Y390481D03*
X59097Y433502D03*
X63563Y460100D03*
X56476D03*
X76500Y66500D03*
X65928Y76500D03*
X72044Y132312D03*
X71970Y135893D03*
X69195Y135799D03*
X69285Y132321D03*
X67126Y128100D03*
X68335Y141369D03*
X68434Y149506D03*
X68432Y152147D03*
X65301Y187762D03*
X67486Y186414D03*
X72000Y235925D03*
X65801Y253145D03*
X76500Y270700D03*
X74000Y270800D03*
X76284Y280470D03*
X75300Y305150D03*
X69500Y308700D03*
X64567Y306665D03*
X73000Y323400D03*
X68757Y352724D03*
X71906Y355873D03*
X75056Y359023D03*
X65607Y349574D03*
X75056Y377883D03*
X68757Y384182D03*
X65607Y387332D03*
X75018Y381033D03*
X69057Y419700D03*
X78800Y423800D03*
X66297Y433002D03*
X70650Y460100D03*
X77500D03*
X82218Y3000D03*
X91700Y66500D03*
X86500Y75000D03*
X88500Y128000D03*
X81800Y188500D03*
X90900Y222850D03*
X85672Y283985D03*
X81864Y297900D03*
X85600Y298100D03*
X82200Y308700D03*
X82022Y303350D03*
X84126Y311790D03*
X79600Y312000D03*
X85500Y323400D03*
X85600Y335000D03*
X87617Y365322D03*
Y371584D03*
X81355Y365322D03*
Y371584D03*
X86300Y397600D03*
X92001Y450402D03*
X82256Y445577D03*
X85276Y445550D03*
X84823Y460100D03*
X91909Y458275D03*
X102218Y3000D03*
X95400Y66500D03*
X98000Y75500D03*
X108727Y99153D03*
X100000Y98500D03*
X105916Y109952D03*
X101230Y127010D03*
X96400Y137475D03*
X97440Y283590D03*
X105000Y311900D03*
X96457Y323194D03*
X97608Y335534D03*
X100215Y352724D03*
X103383Y349556D03*
X93916Y359023D03*
X97066Y355873D03*
X103383Y387350D03*
X100215Y384182D03*
X93916Y377883D03*
X97066Y381033D03*
X103400Y420000D03*
X95280Y412500D03*
X97156Y450437D03*
X94560Y443287D03*
X100225Y443127D03*
X98996Y458275D03*
X106083D03*
X122218Y3000D03*
X111000Y44600D03*
X122500Y58000D03*
X116560Y88651D03*
X120726Y105000D03*
X115200Y98200D03*
X120626Y123500D03*
X112000D03*
X116200Y115100D03*
X119060Y199695D03*
X118300Y237500D03*
X121720Y265330D03*
X111177Y293471D03*
X118009Y313810D03*
Y311200D03*
X115000Y369500D03*
X127900Y45000D03*
X129575Y57375D03*
X129328Y122500D03*
X126575Y111416D03*
X131700Y131000D03*
X133500Y149385D03*
X124500Y167100D03*
X126300Y176575D03*
X135000Y206900D03*
X128900Y255898D03*
X131216Y280187D03*
X124016Y313784D03*
X135462Y313727D03*
X133100Y358900D03*
X133640Y390524D03*
X124287Y406262D03*
X127300Y392600D03*
X129900Y415583D03*
X138500Y457250D03*
X142218Y3000D03*
X147947Y9800D03*
X146800Y79000D03*
X140869Y89055D03*
X141700Y96929D03*
X140869Y104803D03*
Y120551D03*
Y112677D03*
X142000Y146000D03*
X148400Y155765D03*
X153134Y178572D03*
X146390Y224040D03*
X146000Y216350D03*
X141954Y224274D03*
X142300Y216300D03*
X152400Y293400D03*
X150293Y315493D03*
X140700Y370252D03*
X140300Y395100D03*
X152100Y425700D03*
X145365Y426050D03*
X149041Y458750D03*
X162218Y3000D03*
X165700Y11100D03*
X166719Y75874D03*
X168297Y93976D03*
X164429Y93991D03*
X158873Y93976D03*
X166500Y96400D03*
X158420Y116610D03*
X159700Y112000D03*
X161237Y185815D03*
X161240Y190477D03*
X166361Y209794D03*
X166308Y225189D03*
X155800Y234700D03*
X163690Y268610D03*
X164790Y341100D03*
X163800Y356800D03*
X164318Y389102D03*
X157282D03*
X156900Y385700D03*
X154000Y414750D03*
X165194Y428688D03*
X160852Y460118D03*
X182218Y3000D03*
X173853Y93991D03*
X182925Y84300D03*
X180333Y114292D03*
X178346Y200655D03*
Y213254D03*
Y225852D03*
X174079Y234604D03*
X174400Y249136D03*
X173880Y312430D03*
X182372Y325961D03*
X169200Y349400D03*
X180350Y368650D03*
X177082Y387402D03*
X182750Y426750D03*
X187272Y84472D03*
X191312Y84512D03*
X190200Y100500D03*
X198281Y101286D03*
X187360Y132425D03*
X187794Y213254D03*
X196827Y240349D03*
X185897Y249936D03*
X191583Y261363D03*
X189228Y280655D03*
X190922Y350990D03*
X184118Y387402D03*
X185875Y415051D03*
X189600Y459800D03*
X202218Y3000D03*
X207700Y59100D03*
X213100Y69300D03*
X209500Y92326D03*
X211800Y93870D03*
X209824Y106122D03*
X203600Y117000D03*
X203970Y125500D03*
X211200Y140513D03*
X200393Y169197D03*
X203542Y232151D03*
X198990Y247811D03*
X211265Y267300D03*
X207220Y301180D03*
X207750Y366500D03*
X208360Y384890D03*
X203180Y416371D03*
X211865Y444520D03*
X200000Y455800D03*
X209300Y457700D03*
X222218Y3000D03*
X227547Y74275D03*
X219600Y74000D03*
X215800Y69300D03*
X218600D03*
X224958Y107236D03*
X221500Y125100D03*
X217697Y174852D03*
X219290Y191207D03*
X222402Y206955D03*
Y213254D03*
X223672Y290735D03*
X213610Y308800D03*
X223160Y362600D03*
X222225Y407650D03*
X216725D03*
X218085Y444520D03*
X222200Y458700D03*
X215000Y458600D03*
X242218Y3000D03*
X233000Y47100D03*
X230800Y57613D03*
X239347Y79457D03*
X237280Y107510D03*
X229000Y101000D03*
X242812Y117501D03*
X242800Y132200D03*
X231100Y125600D03*
X235001Y166047D03*
X238150Y169197D03*
X232773Y269532D03*
X228800Y302700D03*
X241400Y328100D03*
X233468Y341046D03*
X233300Y356890D03*
X233600Y371500D03*
X233800Y390118D03*
X228230Y390390D03*
X228200Y459100D03*
X248359Y46559D03*
X248700Y75900D03*
X255750Y77350D03*
X250900Y90900D03*
X254397Y103697D03*
X244987Y103528D03*
X251113Y102919D03*
X252300Y107664D03*
X245391Y99589D03*
X252374Y132159D03*
X244450Y159748D03*
X253388Y273655D03*
X246200Y299700D03*
X243410Y381323D03*
X245300Y445800D03*
X262218Y3000D03*
X267022Y12166D03*
X269095Y34625D03*
X260970Y42441D03*
X268675Y74400D03*
X267168Y93768D03*
X260132D03*
X259759Y103651D03*
X259500Y101100D03*
X268435Y121476D03*
X260269Y207358D03*
X261269Y214657D03*
X266200Y300500D03*
X262930Y325300D03*
X259420Y345930D03*
X265922Y354238D03*
X272100Y396300D03*
X265100Y424000D03*
X266300Y435900D03*
X271500Y446800D03*
X269534Y459061D03*
X282218Y3000D03*
X277000Y41982D03*
X282440Y51941D03*
X274219Y51641D03*
X286000Y67975D03*
X274400Y90019D03*
X279200Y114100D03*
X274500Y131629D03*
X279600Y131400D03*
X285980Y163487D03*
X278155Y176085D03*
X286105Y172936D03*
Y182385D03*
Y197989D03*
Y201139D03*
X286000Y242100D03*
X281889Y287636D03*
X276155Y329999D03*
X276100Y375900D03*
Y381500D03*
X284614Y387136D03*
X281300Y419300D03*
X278200Y408700D03*
X277563Y460028D03*
X283707Y459398D03*
X302218Y3000D03*
X300600Y10591D03*
X288856Y12166D03*
X295402Y48051D03*
X290245Y46978D03*
X300856Y104059D03*
X301151Y108649D03*
X301936Y135797D03*
X294200Y128800D03*
X301507Y195435D03*
X289091Y204331D03*
X289254Y210587D03*
Y213737D03*
X301500Y326500D03*
X298748Y390118D03*
X297399Y397382D03*
X290800Y438300D03*
X291689Y453912D03*
Y456912D03*
Y459912D03*
X313977Y33400D03*
X303575Y54516D03*
X304436Y135897D03*
X307500Y125635D03*
X308008Y163487D03*
X311158Y185534D03*
X314307Y191690D03*
X311158Y194839D03*
Y204288D03*
X314307Y207438D03*
X303940Y212664D03*
X311158Y201139D03*
Y213737D03*
X307500Y256500D03*
X312114Y288439D03*
X315810Y293450D03*
X312315Y293207D03*
X317430Y295665D03*
X314820Y296128D03*
X314201Y302361D03*
X314180Y299440D03*
X303077Y297519D03*
X314132Y310178D03*
X314170Y307020D03*
X309500Y315000D03*
X304000Y305000D03*
X311000Y320500D03*
X315075Y366500D03*
X312226Y382766D03*
X322218Y3000D03*
X319175Y60200D03*
X322600Y76100D03*
X331881Y108593D03*
Y104577D03*
Y112608D03*
X320239Y151075D03*
X323384Y157378D03*
X331405Y157411D03*
X323384Y165378D03*
Y161378D03*
Y169378D03*
Y173378D03*
Y177378D03*
X331405Y177411D03*
Y187411D03*
Y192411D03*
X319601Y201140D03*
X317670Y291430D03*
X330900Y314700D03*
X325038Y356890D03*
X325320Y390118D03*
X325200Y383900D03*
X342218Y3000D03*
X337375Y76600D03*
X342900Y66100D03*
X333278Y151129D03*
X337083Y197000D03*
X336312Y286352D03*
X339700Y295900D03*
X342604Y318773D03*
X335700Y376400D03*
X335500Y363200D03*
X334600Y383300D03*
X334112Y447668D03*
X349290Y337646D03*
X374975Y-435380D03*
X374666Y-218571D03*
X374947Y-157108D03*
X374666Y9701D03*
X374975Y71164D03*
X374666Y378973D03*
X380602Y-435533D03*
X380293Y-218724D03*
X380574Y-157261D03*
X380293Y9548D03*
X380602Y71011D03*
X380293Y378820D03*
X396063Y-461442D03*
X401690Y-461595D03*
X401409Y-123786D03*
X395782Y-123633D03*
G54D42*
X451000Y-345000D03*
X441000D03*
X451000Y-235000D03*
X441000D03*
X451000Y106000D03*
X441000D03*
X451000Y210000D03*
X441000D03*
G54D43*
X451000Y-225000D03*
X441000D03*
X451000Y-117000D03*
X441000D03*
X451000Y220000D03*
X441000D03*
X451000Y326000D03*
X441000D03*
G54D27*
X58654Y290605D03*
X104575Y62369D03*
Y67581D03*
G54D13*
X-30100Y263500D03*
G54D12*
X-56100D03*
X-56000Y396000D03*
X-31000Y432000D03*
%LPC*%
G75*
G54D45*
G01X2010999Y-388000D02*
Y1475775D01*
X-407000D01*
Y-386798D01*
Y-755294D01*
Y-793716D01*
X-368578D01*
X1942346D01*
X2010999D01*
Y-725063D01*
Y-388000D01*
G01X-53307Y-609436D02*
Y-684436D01*
X446693D01*
Y-609436D01*
X-53307D01*
G01X-41307Y-674436D02*
Y-679436D01*
G01X-42764Y-674436D02*
X-39850D01*
G01X-34940Y-679436D02*
X-37474D01*
Y-674436D01*
X-34940D01*
G01X-35954Y-676853D02*
X-37474D01*
G01X-32374Y-674436D02*
Y-679436D01*
X-29840D01*
G01X-26007Y-679603D02*
X-26134Y-679519D01*
Y-679353D01*
X-26007Y-679269D01*
X-25880Y-679353D01*
Y-679519D01*
X-26007Y-679603D01*
G01Y-677353D02*
X-26134Y-677269D01*
Y-677103D01*
X-26007Y-677019D01*
X-25880Y-677103D01*
Y-677269D01*
X-26007Y-677353D01*
G01X-21224Y-681103D02*
X-21857Y-680269D01*
X-22174Y-679436D01*
Y-676103D01*
X-21857Y-675269D01*
X-21224Y-674436D01*
G01X-15807D02*
X-16314Y-674603D01*
X-16694Y-675019D01*
X-16947Y-675519D01*
X-17137Y-676186D01*
X-17200Y-676936D01*
X-17137Y-677686D01*
X-16947Y-678353D01*
X-16694Y-678853D01*
X-16314Y-679269D01*
X-15807Y-679436D01*
X-15300Y-679269D01*
X-14920Y-678853D01*
X-14667Y-678353D01*
X-14477Y-677686D01*
X-14414Y-676936D01*
X-14477Y-676186D01*
X-14667Y-675519D01*
X-14920Y-675019D01*
X-15300Y-674603D01*
X-15807Y-674436D01*
G01X-12100Y-678436D02*
X-11720Y-679019D01*
X-11214Y-679353D01*
X-10644Y-679436D01*
X-10137Y-679353D01*
X-9630Y-678936D01*
X-9314Y-678436D01*
X-9250Y-677936D01*
X-9377Y-677353D01*
X-9820Y-676936D01*
X-10264Y-676769D01*
X-10834D01*
G01X-10264D02*
X-9884Y-676519D01*
X-9567Y-676103D01*
X-9440Y-675603D01*
X-9567Y-675103D01*
X-9884Y-674686D01*
X-10454Y-674436D01*
X-11024Y-674519D01*
X-11594Y-674853D01*
G01X-5290Y-681103D02*
X-4657Y-680269D01*
X-4340Y-679436D01*
Y-676103D01*
X-4657Y-675269D01*
X-5290Y-674436D01*
G01X-1900Y-678436D02*
X-1520Y-679019D01*
X-1014Y-679353D01*
X-444Y-679436D01*
X63Y-679353D01*
X570Y-678936D01*
X886Y-678436D01*
X950Y-677936D01*
X823Y-677353D01*
X380Y-676936D01*
X-64Y-676769D01*
X-634D01*
G01X-64D02*
X316Y-676519D01*
X633Y-676103D01*
X760Y-675603D01*
X633Y-675103D01*
X316Y-674686D01*
X-254Y-674436D01*
X-824Y-674519D01*
X-1394Y-674853D01*
G01X3390Y-675269D02*
X3770Y-674769D01*
X4213Y-674519D01*
X4720Y-674436D01*
X5353Y-674603D01*
X5796Y-675019D01*
X5923Y-675519D01*
X5860Y-676019D01*
X5606Y-676436D01*
X4340Y-677269D01*
X3770Y-677853D01*
X3390Y-678686D01*
X3263Y-679436D01*
X5923D01*
G01X9566D02*
X9693Y-678353D01*
X9883Y-677436D01*
X10136Y-676603D01*
X10453Y-675686D01*
X10960Y-674436D01*
X8426D01*
G01X13970Y-677769D02*
X15616D01*
G01X18690Y-675269D02*
X19070Y-674769D01*
X19513Y-674519D01*
X20020Y-674436D01*
X20653Y-674603D01*
X21096Y-675019D01*
X21223Y-675519D01*
X21160Y-676019D01*
X20906Y-676436D01*
X19640Y-677269D01*
X19070Y-677853D01*
X18690Y-678686D01*
X18563Y-679436D01*
X21223D01*
G01X23600Y-678436D02*
X23980Y-679019D01*
X24486Y-679353D01*
X25056Y-679436D01*
X25563Y-679353D01*
X26070Y-678936D01*
X26386Y-678436D01*
X26450Y-677936D01*
X26323Y-677353D01*
X25880Y-676936D01*
X25436Y-676769D01*
X24866D01*
G01X25436D02*
X25816Y-676519D01*
X26133Y-676103D01*
X26260Y-675603D01*
X26133Y-675103D01*
X25816Y-674686D01*
X25246Y-674436D01*
X24676Y-674519D01*
X24106Y-674853D01*
G01X30853Y-679436D02*
Y-674436D01*
X28510Y-678019D01*
X31676D01*
G01X33800Y-678686D02*
X34180Y-679103D01*
X34623Y-679353D01*
X35193Y-679436D01*
X35763Y-679269D01*
X36206Y-678936D01*
X36523Y-678353D01*
X36586Y-677686D01*
X36460Y-677019D01*
X36143Y-676603D01*
X35700Y-676269D01*
X35256Y-676186D01*
X34813Y-676269D01*
X34243Y-676603D01*
X34433Y-674436D01*
X36143D01*
G01X44190Y-679436D02*
Y-674436D01*
X46596D01*
G01X45710Y-676853D02*
X44190D01*
G01X48910Y-679436D02*
X50493Y-674436D01*
X52076Y-679436D01*
G01X51506Y-677686D02*
X49480D01*
G01X54263Y-679436D02*
X56923Y-674436D01*
G01X54263D02*
X56923Y-679436D01*
G01X60693Y-679603D02*
X60566Y-679519D01*
Y-679353D01*
X60693Y-679269D01*
X60820Y-679353D01*
Y-679519D01*
X60693Y-679603D01*
G01Y-677353D02*
X60566Y-677269D01*
Y-677103D01*
X60693Y-677019D01*
X60820Y-677103D01*
Y-677269D01*
X60693Y-677353D01*
G01X65476Y-681103D02*
X64843Y-680269D01*
X64526Y-679436D01*
Y-676103D01*
X64843Y-675269D01*
X65476Y-674436D01*
G01X70893D02*
X70386Y-674603D01*
X70006Y-675019D01*
X69753Y-675519D01*
X69563Y-676186D01*
X69500Y-676936D01*
X69563Y-677686D01*
X69753Y-678353D01*
X70006Y-678853D01*
X70386Y-679269D01*
X70893Y-679436D01*
X71400Y-679269D01*
X71780Y-678853D01*
X72033Y-678353D01*
X72223Y-677686D01*
X72286Y-676936D01*
X72223Y-676186D01*
X72033Y-675519D01*
X71780Y-675019D01*
X71400Y-674603D01*
X70893Y-674436D01*
G01X74600Y-678436D02*
X74980Y-679019D01*
X75486Y-679353D01*
X76056Y-679436D01*
X76563Y-679353D01*
X77070Y-678936D01*
X77386Y-678436D01*
X77450Y-677936D01*
X77323Y-677353D01*
X76880Y-676936D01*
X76436Y-676769D01*
X75866D01*
G01X76436D02*
X76816Y-676519D01*
X77133Y-676103D01*
X77260Y-675603D01*
X77133Y-675103D01*
X76816Y-674686D01*
X76246Y-674436D01*
X75676Y-674519D01*
X75106Y-674853D01*
G01X81410Y-681103D02*
X82043Y-680269D01*
X82360Y-679436D01*
Y-676103D01*
X82043Y-675269D01*
X81410Y-674436D01*
G01X84800Y-678436D02*
X85180Y-679019D01*
X85686Y-679353D01*
X86256Y-679436D01*
X86763Y-679353D01*
X87270Y-678936D01*
X87586Y-678436D01*
X87650Y-677936D01*
X87523Y-677353D01*
X87080Y-676936D01*
X86636Y-676769D01*
X86066D01*
G01X86636D02*
X87016Y-676519D01*
X87333Y-676103D01*
X87460Y-675603D01*
X87333Y-675103D01*
X87016Y-674686D01*
X86446Y-674436D01*
X85876Y-674519D01*
X85306Y-674853D01*
G01X90216Y-678853D02*
X90660Y-679269D01*
X91166Y-679436D01*
X91673Y-679269D01*
X92116Y-678769D01*
X92433Y-678019D01*
X92560Y-677269D01*
Y-676353D01*
X92433Y-675603D01*
X92116Y-674936D01*
X91736Y-674603D01*
X91293Y-674436D01*
X90786Y-674603D01*
X90406Y-674936D01*
X90153Y-675436D01*
X90026Y-676103D01*
X90153Y-676686D01*
X90470Y-677269D01*
X90850Y-677603D01*
X91293Y-677686D01*
X91800Y-677519D01*
X92180Y-677103D01*
X92560Y-676353D01*
G01X96266Y-679436D02*
X96393Y-678353D01*
X96583Y-677436D01*
X96836Y-676603D01*
X97153Y-675686D01*
X97660Y-674436D01*
X95126D01*
G01X100670Y-677769D02*
X102316D01*
G01X105200Y-678436D02*
X105580Y-679019D01*
X106086Y-679353D01*
X106656Y-679436D01*
X107163Y-679353D01*
X107670Y-678936D01*
X107986Y-678436D01*
X108050Y-677936D01*
X107923Y-677353D01*
X107480Y-676936D01*
X107036Y-676769D01*
X106466D01*
G01X107036D02*
X107416Y-676519D01*
X107733Y-676103D01*
X107860Y-675603D01*
X107733Y-675103D01*
X107416Y-674686D01*
X106846Y-674436D01*
X106276Y-674519D01*
X105706Y-674853D01*
G01X110490Y-677353D02*
X110933Y-676769D01*
X111313Y-676436D01*
X111820Y-676269D01*
X112263Y-676436D01*
X112580Y-676769D01*
X112833Y-677269D01*
X112896Y-677853D01*
X112833Y-678353D01*
X112580Y-678853D01*
X112200Y-679269D01*
X111756Y-679436D01*
X111250Y-679269D01*
X110806Y-678769D01*
X110553Y-678019D01*
X110490Y-677186D01*
X110616Y-676103D01*
X110806Y-675519D01*
X111123Y-674936D01*
X111566Y-674519D01*
X112010Y-674436D01*
X112453Y-674603D01*
X112770Y-675019D01*
G01X116793Y-679436D02*
Y-674436D01*
X116033Y-675436D01*
G01Y-679436D02*
X117553D01*
G01X122653D02*
Y-674436D01*
X120310Y-678019D01*
X123476D01*
G01X141693Y-609436D02*
Y-684436D01*
G01Y-659436D02*
X244693D01*
Y-634436D01*
G01X141693D02*
X244693D01*
G01X246693Y-609436D02*
Y-684436D01*
G01X244693Y-609436D02*
Y-684436D01*
G01X252200Y-669436D02*
Y-664436D01*
X253466D01*
X253973Y-664686D01*
X254353Y-665019D01*
X254670Y-665519D01*
X254923Y-666103D01*
X254986Y-666936D01*
X254923Y-667769D01*
X254670Y-668353D01*
X254353Y-668853D01*
X253973Y-669186D01*
X253466Y-669436D01*
X252200D01*
G01X257110D02*
X258693Y-664436D01*
X260276Y-669436D01*
G01X259706Y-667686D02*
X257680D01*
G01X263793Y-664436D02*
Y-669436D01*
G01X262336Y-664436D02*
X265250D01*
G01X270160Y-669436D02*
X267626D01*
Y-664436D01*
X270160D01*
G01X269146Y-666853D02*
X267626D01*
G01X273993Y-669603D02*
X273866Y-669519D01*
Y-669353D01*
X273993Y-669269D01*
X274120Y-669353D01*
Y-669519D01*
X273993Y-669603D01*
G01Y-667353D02*
X273866Y-667269D01*
Y-667103D01*
X273993Y-667019D01*
X274120Y-667103D01*
Y-667269D01*
X273993Y-667353D01*
G01X246693Y-659436D02*
X446693D01*
G01X252326Y-644436D02*
Y-639436D01*
X253846D01*
X254353Y-639686D01*
X254733Y-640269D01*
X254860Y-640936D01*
X254733Y-641603D01*
X254416Y-642103D01*
X253846Y-642353D01*
X252326D01*
G01X257553Y-644603D02*
X259833Y-639436D01*
G01X262336Y-644436D02*
Y-639436D01*
X265250Y-644436D01*
Y-639436D01*
G01X268893Y-644603D02*
X268766Y-644519D01*
Y-644353D01*
X268893Y-644269D01*
X269020Y-644353D01*
Y-644519D01*
X268893Y-644603D01*
G01Y-642353D02*
X268766Y-642269D01*
Y-642103D01*
X268893Y-642019D01*
X269020Y-642103D01*
Y-642269D01*
X268893Y-642353D01*
G01X246693Y-634436D02*
X446693D01*
G01X252326Y-619436D02*
Y-614436D01*
X253846D01*
X254353Y-614686D01*
X254733Y-615269D01*
X254860Y-615936D01*
X254733Y-616603D01*
X254416Y-617103D01*
X253846Y-617353D01*
X252326D01*
G01X257426Y-619436D02*
Y-614436D01*
X259010D01*
X259516Y-614686D01*
X259833Y-615019D01*
X259960Y-615686D01*
X259833Y-616353D01*
X259453Y-616769D01*
X259010Y-617019D01*
X257426D01*
G01X259010D02*
X259960Y-619436D01*
G01X263793D02*
X263286Y-619353D01*
X262843Y-619019D01*
X262463Y-618519D01*
X262210Y-617936D01*
X262083Y-617269D01*
Y-616603D01*
X262210Y-615936D01*
X262463Y-615353D01*
X262843Y-614853D01*
X263286Y-614519D01*
X263793Y-614436D01*
X264300Y-614519D01*
X264743Y-614853D01*
X265123Y-615353D01*
X265376Y-615936D01*
X265503Y-616603D01*
Y-617269D01*
X265376Y-617936D01*
X265123Y-618519D01*
X264743Y-619019D01*
X264300Y-619353D01*
X263793Y-619436D01*
G01X267626Y-618436D02*
X267943Y-618936D01*
X268323Y-619269D01*
X268766Y-619436D01*
X269273Y-619269D01*
X269653Y-618936D01*
X270033Y-618436D01*
X270160Y-617769D01*
Y-614436D01*
G01X275260Y-619436D02*
X272726D01*
Y-614436D01*
X275260D01*
G01X274246Y-616853D02*
X272726D01*
G01X280486Y-614853D02*
X280106Y-614603D01*
X279663Y-614436D01*
X279156D01*
X278586Y-614686D01*
X278143Y-615103D01*
X277826Y-615603D01*
X277573Y-616436D01*
X277510Y-617186D01*
X277636Y-617936D01*
X277826Y-618436D01*
X278206Y-618936D01*
X278650Y-619269D01*
X279093Y-619436D01*
X279536D01*
X279980Y-619269D01*
X280360Y-619019D01*
X280676Y-618686D01*
G01X284193Y-614436D02*
Y-619436D01*
G01X282736Y-614436D02*
X285650D01*
G01X289293Y-619603D02*
X289166Y-619519D01*
Y-619353D01*
X289293Y-619269D01*
X289420Y-619353D01*
Y-619519D01*
X289293Y-619603D01*
G01Y-617353D02*
X289166Y-617269D01*
Y-617103D01*
X289293Y-617019D01*
X289420Y-617103D01*
Y-617269D01*
X289293Y-617353D01*
G01X361693Y-659436D02*
Y-684436D01*
G01X364326Y-661936D02*
Y-666936D01*
X366860D01*
G01X369933Y-661936D02*
X371453D01*
G01X370693D02*
Y-666936D01*
G01X369933D02*
X371453D01*
G01X376300Y-664269D02*
X376553Y-664019D01*
X376743Y-663603D01*
X376870Y-663019D01*
X376743Y-662519D01*
X376490Y-662186D01*
X376046Y-661936D01*
X374336D01*
Y-666936D01*
X376426D01*
X376870Y-666603D01*
X377123Y-666103D01*
X377250Y-665519D01*
X377123Y-664936D01*
X376743Y-664436D01*
X376300Y-664269D01*
X374336D01*
G01X380893Y-667103D02*
X380766Y-667019D01*
Y-666853D01*
X380893Y-666769D01*
X381020Y-666853D01*
Y-667019D01*
X380893Y-667103D01*
G01Y-664853D02*
X380766Y-664769D01*
Y-664603D01*
X380893Y-664519D01*
X381020Y-664603D01*
Y-664769D01*
X380893Y-664853D01*
G01X404693Y-659436D02*
Y-684436D01*
G01Y-634436D02*
Y-659436D01*
G01X412706Y-687603D02*
X412813Y-687478D01*
X412893Y-687269D01*
X412946Y-686978D01*
X412893Y-686728D01*
X412786Y-686561D01*
X412600Y-686436D01*
X411880D01*
Y-688936D01*
X412760D01*
X412946Y-688769D01*
X413053Y-688519D01*
X413106Y-688228D01*
X413053Y-687936D01*
X412893Y-687686D01*
X412706Y-687603D01*
X411880D01*
G01X415173Y-688936D02*
Y-687269D01*
G01Y-687561D02*
X415066Y-687394D01*
X414906Y-687311D01*
X414720Y-687269D01*
X414533Y-687353D01*
X414373Y-687519D01*
X414266Y-687769D01*
X414213Y-688103D01*
X414266Y-688436D01*
X414373Y-688686D01*
X414533Y-688853D01*
X414720Y-688936D01*
X414906Y-688894D01*
X415066Y-688769D01*
X415173Y-688603D01*
G01X416493Y-688644D02*
X416626Y-688811D01*
X416813Y-688936D01*
X416973D01*
X417133Y-688853D01*
X417240Y-688728D01*
X417293Y-688561D01*
X417266Y-688311D01*
X417160Y-688186D01*
X416680Y-687936D01*
X416573Y-687644D01*
X416626Y-687436D01*
X416733Y-687311D01*
X416893Y-687269D01*
X417053Y-687311D01*
X417213Y-687436D01*
G01X418693Y-687811D02*
X419546D01*
X419466Y-687519D01*
X419333Y-687353D01*
X419146Y-687269D01*
X418960Y-687311D01*
X418800Y-687436D01*
X418693Y-687728D01*
X418640Y-687978D01*
Y-688228D01*
X418693Y-688478D01*
X418826Y-688728D01*
X418986Y-688894D01*
X419173Y-688936D01*
X419360Y-688853D01*
X419546Y-688603D01*
G01X420813Y-688936D02*
Y-686436D01*
G01Y-687686D02*
X420946Y-687436D01*
X421106Y-687311D01*
X421266Y-687269D01*
X421506Y-687353D01*
X421666Y-687519D01*
X421773Y-687811D01*
Y-688144D01*
X421720Y-688478D01*
X421613Y-688728D01*
X421426Y-688894D01*
X421266Y-688936D01*
X421106Y-688894D01*
X420946Y-688769D01*
X420813Y-688561D01*
G01X423493Y-688936D02*
X423333Y-688894D01*
X423173Y-688728D01*
X423066Y-688436D01*
X423013Y-688103D01*
X423066Y-687769D01*
X423173Y-687478D01*
X423333Y-687311D01*
X423493Y-687269D01*
X423653Y-687311D01*
X423813Y-687478D01*
X423920Y-687769D01*
X423946Y-688103D01*
X423920Y-688436D01*
X423813Y-688728D01*
X423653Y-688894D01*
X423493Y-688936D01*
G01X426173D02*
Y-687269D01*
G01Y-687561D02*
X426066Y-687394D01*
X425906Y-687311D01*
X425720Y-687269D01*
X425533Y-687353D01*
X425373Y-687519D01*
X425266Y-687769D01*
X425213Y-688103D01*
X425266Y-688436D01*
X425373Y-688686D01*
X425533Y-688853D01*
X425720Y-688936D01*
X425906Y-688894D01*
X426066Y-688769D01*
X426173Y-688603D01*
G01X427520Y-688936D02*
Y-687269D01*
G01Y-687603D02*
X427653Y-687436D01*
X427786Y-687311D01*
X427973Y-687269D01*
X428106Y-687311D01*
X428266Y-687436D01*
G01X430573Y-686436D02*
Y-688936D01*
G01Y-688561D02*
X430466Y-688769D01*
X430306Y-688894D01*
X430120Y-688936D01*
X429906Y-688853D01*
X429746Y-688644D01*
X429640Y-688394D01*
X429613Y-688103D01*
X429640Y-687811D01*
X429746Y-687561D01*
X429906Y-687353D01*
X430120Y-687269D01*
X430306Y-687311D01*
X430440Y-687394D01*
X430573Y-687561D01*
G01X433960Y-688936D02*
Y-686436D01*
X434626D01*
X434840Y-686561D01*
X434973Y-686728D01*
X435026Y-687061D01*
X434973Y-687394D01*
X434813Y-687603D01*
X434626Y-687728D01*
X433960D01*
G01X434626D02*
X435026Y-688936D01*
G01X436293Y-687811D02*
X437146D01*
X437066Y-687519D01*
X436933Y-687353D01*
X436746Y-687269D01*
X436560Y-687311D01*
X436400Y-687436D01*
X436293Y-687728D01*
X436240Y-687978D01*
Y-688228D01*
X436293Y-688478D01*
X436426Y-688728D01*
X436586Y-688894D01*
X436773Y-688936D01*
X436960Y-688853D01*
X437146Y-688603D01*
G01X438413Y-687269D02*
X438893Y-688936D01*
X439373Y-687269D01*
G01X441093Y-689019D02*
X441040Y-688978D01*
Y-688894D01*
X441093Y-688853D01*
X441146Y-688894D01*
Y-688978D01*
X441093Y-689019D01*
G01X443613Y-688936D02*
Y-686436D01*
X442626Y-688228D01*
X443960D01*
G01X444826Y-688936D02*
X445493Y-686436D01*
X446160Y-688936D01*
G01X445920Y-688061D02*
X445066D01*
G01X408593Y-661936D02*
Y-666936D01*
G01X407136Y-661936D02*
X410050D01*
G01X413693Y-666936D02*
X413313Y-666853D01*
X412933Y-666519D01*
X412680Y-665936D01*
X412553Y-665269D01*
X412680Y-664603D01*
X412933Y-664019D01*
X413313Y-663686D01*
X413693Y-663603D01*
X414073Y-663686D01*
X414453Y-664019D01*
X414706Y-664603D01*
X414770Y-665269D01*
X414706Y-665936D01*
X414453Y-666519D01*
X414073Y-666853D01*
X413693Y-666936D01*
G01X418793D02*
X418413Y-666853D01*
X418033Y-666519D01*
X417780Y-665936D01*
X417653Y-665269D01*
X417780Y-664603D01*
X418033Y-664019D01*
X418413Y-663686D01*
X418793Y-663603D01*
X419173Y-663686D01*
X419553Y-664019D01*
X419806Y-664603D01*
X419870Y-665269D01*
X419806Y-665936D01*
X419553Y-666519D01*
X419173Y-666853D01*
X418793Y-666936D01*
G01X423893D02*
Y-661936D01*
G01X428993Y-667103D02*
X428866Y-667019D01*
Y-666853D01*
X428993Y-666769D01*
X429120Y-666853D01*
Y-667019D01*
X428993Y-667103D01*
G01Y-664853D02*
X428866Y-664769D01*
Y-664603D01*
X428993Y-664519D01*
X429120Y-664603D01*
Y-664769D01*
X428993Y-664853D01*
G01X407326Y-641936D02*
Y-636936D01*
X408910D01*
X409416Y-637186D01*
X409733Y-637519D01*
X409860Y-638186D01*
X409733Y-638853D01*
X409353Y-639269D01*
X408910Y-639519D01*
X407326D01*
G01X408910D02*
X409860Y-641936D01*
G01X414960D02*
X412426D01*
Y-636936D01*
X414960D01*
G01X413946Y-639353D02*
X412426D01*
G01X417210Y-636936D02*
X418793Y-641936D01*
X420376Y-636936D01*
G01X423893Y-642103D02*
X423766Y-642019D01*
Y-641853D01*
X423893Y-641769D01*
X424020Y-641853D01*
Y-642019D01*
X423893Y-642103D01*
G01Y-639853D02*
X423766Y-639769D01*
Y-639603D01*
X423893Y-639519D01*
X424020Y-639603D01*
Y-639769D01*
X423893Y-639853D01*
G01X2010999Y-388000D02*
Y1475775D01*
X-407000D01*
Y-386798D01*
Y-755294D01*
Y-793716D01*
X-368578D01*
X1942346D01*
X2010999D01*
Y-725063D01*
Y-388000D01*
G01X-42602Y-671096D02*
X-41975Y-671621D01*
X-41270Y-671936D01*
X-40644D01*
X-40017Y-671621D01*
X-39547Y-671096D01*
X-39312Y-670361D01*
X-39469Y-669626D01*
X-39860Y-668996D01*
X-40565Y-668576D01*
X-41505Y-668366D01*
X-42054Y-667946D01*
X-42289Y-667211D01*
X-42132Y-666476D01*
X-41740Y-665951D01*
X-41192Y-665636D01*
X-40644D01*
X-40095Y-665846D01*
X-39625Y-666371D01*
G01X-36302Y-671936D02*
Y-665636D01*
G01X-33012D02*
Y-671936D01*
G01Y-668786D02*
X-36302D01*
G01X-29297Y-665636D02*
X-27417D01*
G01X-28357D02*
Y-671936D01*
G01X-29297D02*
X-27417D01*
G01X-20490D02*
X-23624D01*
Y-665636D01*
X-20490D01*
G01X-21744Y-668681D02*
X-23624D01*
G01X-17559Y-671936D02*
Y-665636D01*
X-13955Y-671936D01*
Y-665636D01*
G01X-9614Y-673091D02*
X-9300Y-671726D01*
G01X-3157Y-665636D02*
Y-671936D01*
G01X-4959Y-665636D02*
X-1355D01*
G01X1185Y-671936D02*
X3143Y-665636D01*
X5101Y-671936D01*
G01X4396Y-669731D02*
X1890D01*
G01X8503Y-665636D02*
X10383D01*
G01X9443D02*
Y-671936D01*
G01X8503D02*
X10383D01*
G01X13393Y-665636D02*
X14490Y-671936D01*
X15743Y-665636D01*
X16996Y-671936D01*
X18093Y-665636D01*
G01X20085Y-671936D02*
X22043Y-665636D01*
X24001Y-671936D01*
G01X23296Y-669731D02*
X20790D01*
G01X26541Y-671936D02*
Y-665636D01*
X30145Y-671936D01*
Y-665636D01*
G01X39376Y-671936D02*
Y-665636D01*
X41335D01*
X41961Y-665951D01*
X42353Y-666371D01*
X42510Y-667211D01*
X42353Y-668051D01*
X41883Y-668576D01*
X41335Y-668891D01*
X39376D01*
G01X41335D02*
X42510Y-671936D01*
G01X47243Y-672146D02*
X47086Y-672041D01*
Y-671831D01*
X47243Y-671726D01*
X47400Y-671831D01*
Y-672041D01*
X47243Y-672146D01*
G01X53543Y-671936D02*
X52916Y-671831D01*
X52368Y-671411D01*
X51898Y-670781D01*
X51585Y-670046D01*
X51428Y-669206D01*
Y-668366D01*
X51585Y-667526D01*
X51898Y-666791D01*
X52368Y-666161D01*
X52916Y-665741D01*
X53543Y-665636D01*
X54170Y-665741D01*
X54718Y-666161D01*
X55188Y-666791D01*
X55501Y-667526D01*
X55658Y-668366D01*
Y-669206D01*
X55501Y-670046D01*
X55188Y-670781D01*
X54718Y-671411D01*
X54170Y-671831D01*
X53543Y-671936D01*
G01X59843Y-672146D02*
X59686Y-672041D01*
Y-671831D01*
X59843Y-671726D01*
X60000Y-671831D01*
Y-672041D01*
X59843Y-672146D01*
G01X67866Y-666161D02*
X67396Y-665846D01*
X66848Y-665636D01*
X66221D01*
X65516Y-665951D01*
X64968Y-666476D01*
X64576Y-667106D01*
X64263Y-668156D01*
X64185Y-669101D01*
X64341Y-670046D01*
X64576Y-670676D01*
X65046Y-671306D01*
X65595Y-671726D01*
X66143Y-671936D01*
X66691D01*
X67240Y-671726D01*
X67710Y-671411D01*
X68101Y-670991D01*
G01X72443Y-672146D02*
X72286Y-672041D01*
Y-671831D01*
X72443Y-671726D01*
X72600Y-671831D01*
Y-672041D01*
X72443Y-672146D01*
G01X-42680Y-661936D02*
Y-655636D01*
G01X-39704D02*
X-42680Y-659521D01*
G01X-39234Y-661936D02*
X-41349Y-657736D01*
G01X-36380Y-655636D02*
Y-660151D01*
X-36067Y-661096D01*
X-35440Y-661726D01*
X-34657Y-661936D01*
X-33874Y-661726D01*
X-33247Y-661096D01*
X-32934Y-660151D01*
Y-655636D01*
G01X-26790Y-661936D02*
X-29924D01*
Y-655636D01*
X-26790D01*
G01X-28044Y-658681D02*
X-29924D01*
G01X-22997Y-655636D02*
X-21117D01*
G01X-22057D02*
Y-661936D01*
G01X-22997D02*
X-21117D01*
G01X-11102Y-661096D02*
X-10475Y-661621D01*
X-9770Y-661936D01*
X-9144D01*
X-8517Y-661621D01*
X-8047Y-661096D01*
X-7812Y-660361D01*
X-7969Y-659626D01*
X-8360Y-658996D01*
X-9065Y-658576D01*
X-10005Y-658366D01*
X-10554Y-657946D01*
X-10789Y-657211D01*
X-10632Y-656476D01*
X-10240Y-655951D01*
X-9692Y-655636D01*
X-9144D01*
X-8595Y-655846D01*
X-8125Y-656371D01*
G01X-4802Y-661936D02*
Y-655636D01*
G01X-1512D02*
Y-661936D01*
G01Y-658786D02*
X-4802D01*
G01X1185Y-661936D02*
X3143Y-655636D01*
X5101Y-661936D01*
G01X4396Y-659731D02*
X1890D01*
G01X7641Y-661936D02*
Y-655636D01*
X11245Y-661936D01*
Y-655636D01*
G01X20398Y-661936D02*
Y-655636D01*
G01X23688D02*
Y-661936D01*
G01Y-658786D02*
X20398D01*
G01X26698Y-661096D02*
X27325Y-661621D01*
X28030Y-661936D01*
X28656D01*
X29283Y-661621D01*
X29753Y-661096D01*
X29988Y-660361D01*
X29831Y-659626D01*
X29440Y-658996D01*
X28735Y-658576D01*
X27795Y-658366D01*
X27246Y-657946D01*
X27011Y-657211D01*
X27168Y-656476D01*
X27560Y-655951D01*
X28108Y-655636D01*
X28656D01*
X29205Y-655846D01*
X29675Y-656371D01*
G01X33703Y-655636D02*
X35583D01*
G01X34643D02*
Y-661936D01*
G01X33703D02*
X35583D01*
G01X38985D02*
X40943Y-655636D01*
X42901Y-661936D01*
G01X42196Y-659731D02*
X39690D01*
G01X45441Y-661936D02*
Y-655636D01*
X49045Y-661936D01*
Y-655636D01*
G01X54013Y-658786D02*
X55580D01*
Y-660676D01*
X55110Y-661306D01*
X54561Y-661726D01*
X53778Y-661936D01*
X52995Y-661726D01*
X52446Y-661306D01*
X51976Y-660676D01*
X51663Y-659941D01*
X51506Y-659101D01*
Y-658366D01*
X51663Y-657736D01*
X51976Y-657001D01*
X52446Y-656371D01*
X52916Y-655951D01*
X53543Y-655636D01*
X54091D01*
X54718Y-655846D01*
X55188Y-656266D01*
G01X59686Y-663091D02*
X60000Y-661726D01*
G01X66143Y-655636D02*
Y-661936D01*
G01X64341Y-655636D02*
X67945D01*
G01X70485Y-661936D02*
X72443Y-655636D01*
X74401Y-661936D01*
G01X73696Y-659731D02*
X71190D01*
G01X78743Y-661936D02*
X78116Y-661831D01*
X77568Y-661411D01*
X77098Y-660781D01*
X76785Y-660046D01*
X76628Y-659206D01*
Y-658366D01*
X76785Y-657526D01*
X77098Y-656791D01*
X77568Y-656161D01*
X78116Y-655741D01*
X78743Y-655636D01*
X79370Y-655741D01*
X79918Y-656161D01*
X80388Y-656791D01*
X80701Y-657526D01*
X80858Y-658366D01*
Y-659206D01*
X80701Y-660046D01*
X80388Y-660781D01*
X79918Y-661411D01*
X79370Y-661831D01*
X78743Y-661936D01*
G01X91343D02*
Y-659101D01*
X89776Y-655636D01*
G01X92910D02*
X91343Y-659101D01*
G01X95920Y-655636D02*
Y-660151D01*
X96233Y-661096D01*
X96860Y-661726D01*
X97643Y-661936D01*
X98426Y-661726D01*
X99053Y-661096D01*
X99366Y-660151D01*
Y-655636D01*
G01X101985Y-661936D02*
X103943Y-655636D01*
X105901Y-661936D01*
G01X105196Y-659731D02*
X102690D01*
G01X108441Y-661936D02*
Y-655636D01*
X112045Y-661936D01*
Y-655636D01*
G01X-42759Y-651936D02*
Y-645636D01*
X-39155Y-651936D01*
Y-645636D01*
G01X-34657Y-651936D02*
X-35284Y-651831D01*
X-35832Y-651411D01*
X-36302Y-650781D01*
X-36615Y-650046D01*
X-36772Y-649206D01*
Y-648366D01*
X-36615Y-647526D01*
X-36302Y-646791D01*
X-35832Y-646161D01*
X-35284Y-645741D01*
X-34657Y-645636D01*
X-34030Y-645741D01*
X-33482Y-646161D01*
X-33012Y-646791D01*
X-32699Y-647526D01*
X-32542Y-648366D01*
Y-649206D01*
X-32699Y-650046D01*
X-33012Y-650781D01*
X-33482Y-651411D01*
X-34030Y-651831D01*
X-34657Y-651936D01*
G01X-28357Y-652146D02*
X-28514Y-652041D01*
Y-651831D01*
X-28357Y-651726D01*
X-28200Y-651831D01*
Y-652041D01*
X-28357Y-652146D01*
G01X-22057Y-651936D02*
Y-645636D01*
X-22997Y-646896D01*
G01Y-651936D02*
X-21117D01*
G01X-15757D02*
X-15209Y-651831D01*
X-14582Y-651516D01*
X-14190Y-650991D01*
X-14034Y-650256D01*
X-14190Y-649521D01*
X-14660Y-648891D01*
X-15365Y-648576D01*
X-16149D01*
X-16619Y-648366D01*
X-17010Y-647841D01*
X-17167Y-647106D01*
X-16932Y-646371D01*
X-16384Y-645846D01*
X-15757Y-645636D01*
X-15130Y-645846D01*
X-14582Y-646371D01*
X-14347Y-647106D01*
X-14504Y-647841D01*
X-14895Y-648366D01*
X-15365Y-648576D01*
X-16149D01*
X-16854Y-648891D01*
X-17324Y-649521D01*
X-17480Y-650256D01*
X-17324Y-650991D01*
X-16932Y-651516D01*
X-16305Y-651831D01*
X-15757Y-651936D01*
G01X-9457D02*
X-8909Y-651831D01*
X-8282Y-651516D01*
X-7890Y-650991D01*
X-7734Y-650256D01*
X-7890Y-649521D01*
X-8360Y-648891D01*
X-9065Y-648576D01*
X-9849D01*
X-10319Y-648366D01*
X-10710Y-647841D01*
X-10867Y-647106D01*
X-10632Y-646371D01*
X-10084Y-645846D01*
X-9457Y-645636D01*
X-8830Y-645846D01*
X-8282Y-646371D01*
X-8047Y-647106D01*
X-8204Y-647841D01*
X-8595Y-648366D01*
X-9065Y-648576D01*
X-9849D01*
X-10554Y-648891D01*
X-11024Y-649521D01*
X-11180Y-650256D01*
X-11024Y-650991D01*
X-10632Y-651516D01*
X-10005Y-651831D01*
X-9457Y-651936D01*
G01X-3314Y-653091D02*
X-3000Y-651726D01*
G01X793Y-645636D02*
X1890Y-651936D01*
X3143Y-645636D01*
X4396Y-651936D01*
X5493Y-645636D01*
G01X11010Y-651936D02*
X7876D01*
Y-645636D01*
X11010D01*
G01X9756Y-648681D02*
X7876D01*
G01X13941Y-651936D02*
Y-645636D01*
X17545Y-651936D01*
Y-645636D01*
G01X26698Y-651936D02*
Y-645636D01*
G01X29988D02*
Y-651936D01*
G01Y-648786D02*
X26698D01*
G01X32293Y-645636D02*
X33390Y-651936D01*
X34643Y-645636D01*
X35896Y-651936D01*
X36993Y-645636D01*
G01X38985Y-651936D02*
X40943Y-645636D01*
X42901Y-651936D01*
G01X42196Y-649731D02*
X39690D01*
G01X52055Y-646686D02*
X52525Y-646056D01*
X53073Y-645741D01*
X53700Y-645636D01*
X54483Y-645846D01*
X55031Y-646371D01*
X55188Y-647001D01*
X55110Y-647631D01*
X54796Y-648156D01*
X53230Y-649206D01*
X52525Y-649941D01*
X52055Y-650991D01*
X51898Y-651936D01*
X55188D01*
G01X58041D02*
Y-645636D01*
X61645Y-651936D01*
Y-645636D01*
G01X64420Y-651936D02*
Y-645636D01*
X65986D01*
X66613Y-645951D01*
X67083Y-646371D01*
X67475Y-647001D01*
X67788Y-647736D01*
X67866Y-648786D01*
X67788Y-649836D01*
X67475Y-650571D01*
X67083Y-651201D01*
X66613Y-651621D01*
X65986Y-651936D01*
X64420D01*
G01X77176D02*
Y-645636D01*
X79135D01*
X79761Y-645951D01*
X80153Y-646371D01*
X80310Y-647211D01*
X80153Y-648051D01*
X79683Y-648576D01*
X79135Y-648891D01*
X77176D01*
G01X79135D02*
X80310Y-651936D01*
G01X83320D02*
Y-645636D01*
X84886D01*
X85513Y-645951D01*
X85983Y-646371D01*
X86375Y-647001D01*
X86688Y-647736D01*
X86766Y-648786D01*
X86688Y-649836D01*
X86375Y-650571D01*
X85983Y-651201D01*
X85513Y-651621D01*
X84886Y-651936D01*
X83320D01*
G01X91343Y-652146D02*
X91186Y-652041D01*
Y-651831D01*
X91343Y-651726D01*
X91500Y-651831D01*
Y-652041D01*
X91343Y-652146D01*
G01X-18657Y-639236D02*
X-21177Y-638819D01*
X-23382Y-637153D01*
X-25272Y-634653D01*
X-26532Y-631736D01*
X-27162Y-628403D01*
Y-625069D01*
X-26532Y-621736D01*
X-25272Y-618819D01*
X-23382Y-616320D01*
X-21177Y-614653D01*
X-18657Y-614236D01*
X-16137Y-614653D01*
X-13932Y-616320D01*
X-12042Y-618819D01*
X-10782Y-621736D01*
X-10152Y-625069D01*
Y-628403D01*
X-10782Y-631736D01*
X-12042Y-634653D01*
X-13932Y-637153D01*
X-16137Y-638819D01*
X-18657Y-639236D01*
G01X-16137Y-632569D02*
X-12357Y-639236D01*
G01X1188Y-622570D02*
Y-634236D01*
X2448Y-637153D01*
X4338Y-638819D01*
X6543Y-639236D01*
X8748Y-638819D01*
X10638Y-637153D01*
X11898Y-634236D01*
G01Y-639236D02*
Y-622570D01*
G01X37413Y-639236D02*
Y-622570D01*
G01Y-625486D02*
X36153Y-623820D01*
X34263Y-622986D01*
X32058Y-622570D01*
X29853Y-623403D01*
X27963Y-625069D01*
X26703Y-627570D01*
X26073Y-630903D01*
X26703Y-634236D01*
X27963Y-636737D01*
X29853Y-638403D01*
X32058Y-639236D01*
X34263Y-638819D01*
X36153Y-637570D01*
X37413Y-635903D01*
G01X51588Y-639236D02*
Y-622570D01*
G01Y-626736D02*
X52848Y-624653D01*
X54738Y-622986D01*
X57258Y-622570D01*
X59463Y-622986D01*
X61353Y-624653D01*
X62298Y-627570D01*
Y-639236D01*
G01X82143Y-614236D02*
Y-639236D01*
G01X77733Y-622570D02*
X86553D01*
G01X113013Y-639236D02*
Y-622570D01*
G01Y-625486D02*
X111753Y-623820D01*
X109863Y-622986D01*
X107658Y-622570D01*
X105453Y-623403D01*
X103563Y-625069D01*
X102303Y-627570D01*
X101673Y-630903D01*
X102303Y-634236D01*
X103563Y-636737D01*
X105453Y-638403D01*
X107658Y-639236D01*
X109863Y-638819D01*
X111753Y-637570D01*
X113013Y-635903D01*
G01X152693Y-618936D02*
Y-626936D01*
X156693D01*
G01X164493D02*
Y-621603D01*
G01Y-622536D02*
X164093Y-622003D01*
X163493Y-621736D01*
X162793Y-621603D01*
X162093Y-621869D01*
X161493Y-622403D01*
X161093Y-623203D01*
X160893Y-624269D01*
X161093Y-625336D01*
X161493Y-626136D01*
X162093Y-626669D01*
X162793Y-626936D01*
X163493Y-626803D01*
X164093Y-626403D01*
X164493Y-625870D01*
G01X168593Y-629336D02*
X169193Y-629603D01*
X169993Y-629336D01*
X170493Y-628803D01*
X170893Y-628136D01*
X171493Y-626003D01*
X172793Y-621603D01*
G01X169593D02*
X171493Y-626003D01*
G01X177193Y-623336D02*
X180393D01*
X180093Y-622403D01*
X179593Y-621869D01*
X178893Y-621603D01*
X178193Y-621736D01*
X177593Y-622136D01*
X177193Y-623069D01*
X176993Y-623870D01*
Y-624669D01*
X177193Y-625469D01*
X177693Y-626269D01*
X178293Y-626803D01*
X178993Y-626936D01*
X179693Y-626669D01*
X180393Y-625870D01*
G01X185293Y-626936D02*
Y-621603D01*
G01Y-622669D02*
X185793Y-622136D01*
X186293Y-621736D01*
X186993Y-621603D01*
X187493Y-621736D01*
X188093Y-622136D01*
G01X173993Y-676936D02*
Y-668936D01*
G01X177793D02*
X173993Y-673870D01*
G01X178393Y-676936D02*
X175693Y-671603D01*
G01X185993Y-676936D02*
Y-671603D01*
G01Y-672536D02*
X185593Y-672003D01*
X184993Y-671736D01*
X184293Y-671603D01*
X183593Y-671869D01*
X182993Y-672403D01*
X182593Y-673203D01*
X182393Y-674269D01*
X182593Y-675336D01*
X182993Y-676136D01*
X183593Y-676669D01*
X184293Y-676936D01*
X184993Y-676803D01*
X185593Y-676403D01*
X185993Y-675870D01*
G01X192193Y-671603D02*
Y-676936D01*
G01Y-669469D02*
X191993Y-669336D01*
Y-669069D01*
X192193Y-668936D01*
X192393Y-669069D01*
Y-669336D01*
X192193Y-669469D01*
G01X184293Y-647936D02*
X186293D01*
Y-650336D01*
X185693Y-651136D01*
X184993Y-651669D01*
X183993Y-651936D01*
X182993Y-651669D01*
X182293Y-651136D01*
X181693Y-650336D01*
X181293Y-649403D01*
X181093Y-648336D01*
Y-647403D01*
X181293Y-646603D01*
X181693Y-645669D01*
X182293Y-644869D01*
X182893Y-644336D01*
X183693Y-643936D01*
X184393D01*
X185193Y-644203D01*
X185793Y-644736D01*
G01X189393Y-651936D02*
Y-643936D01*
X193993Y-651936D01*
Y-643936D01*
G01X197493Y-651936D02*
Y-643936D01*
X199493D01*
X200293Y-644336D01*
X200893Y-644869D01*
X201393Y-645669D01*
X201793Y-646603D01*
X201893Y-647936D01*
X201793Y-649269D01*
X201393Y-650203D01*
X200893Y-651003D01*
X200293Y-651536D01*
X199493Y-651936D01*
X197493D01*
G01X207693D02*
Y-643936D01*
X206493Y-645536D01*
G01Y-651936D02*
X208893D01*
G01X207393Y-626936D02*
Y-618936D01*
X203693Y-624669D01*
X208693D01*
G01X279293Y-670269D02*
X279893Y-669469D01*
X280593Y-669069D01*
X281393Y-668936D01*
X282393Y-669203D01*
X283093Y-669869D01*
X283293Y-670669D01*
X283193Y-671470D01*
X282793Y-672136D01*
X280793Y-673469D01*
X279893Y-674403D01*
X279293Y-675736D01*
X279093Y-676936D01*
X283293D01*
G01X289193Y-668936D02*
X288393Y-669203D01*
X287793Y-669869D01*
X287393Y-670669D01*
X287093Y-671736D01*
X286993Y-672936D01*
X287093Y-674136D01*
X287393Y-675203D01*
X287793Y-676003D01*
X288393Y-676669D01*
X289193Y-676936D01*
X289993Y-676669D01*
X290593Y-676003D01*
X290993Y-675203D01*
X291293Y-674136D01*
X291393Y-672936D01*
X291293Y-671736D01*
X290993Y-670669D01*
X290593Y-669869D01*
X289993Y-669203D01*
X289193Y-668936D01*
G01X295293Y-670269D02*
X295893Y-669469D01*
X296593Y-669069D01*
X297393Y-668936D01*
X298393Y-669203D01*
X299093Y-669869D01*
X299293Y-670669D01*
X299193Y-671470D01*
X298793Y-672136D01*
X296793Y-673469D01*
X295893Y-674403D01*
X295293Y-675736D01*
X295093Y-676936D01*
X299293D01*
G01X303293Y-670269D02*
X303893Y-669469D01*
X304593Y-669069D01*
X305393Y-668936D01*
X306393Y-669203D01*
X307093Y-669869D01*
X307293Y-670669D01*
X307193Y-671470D01*
X306793Y-672136D01*
X304793Y-673469D01*
X303893Y-674403D01*
X303293Y-675736D01*
X303093Y-676936D01*
X307293D01*
G01X311393Y-677203D02*
X314993Y-668936D01*
G01X321193Y-676936D02*
Y-668936D01*
X319993Y-670536D01*
G01Y-676936D02*
X322393D01*
G01X327293Y-670269D02*
X327893Y-669469D01*
X328593Y-669069D01*
X329393Y-668936D01*
X330393Y-669203D01*
X331093Y-669869D01*
X331293Y-670669D01*
X331193Y-671470D01*
X330793Y-672136D01*
X328793Y-673469D01*
X327893Y-674403D01*
X327293Y-675736D01*
X327093Y-676936D01*
X331293D01*
G01X335393Y-677203D02*
X338993Y-668936D01*
G01X345193D02*
X344393Y-669203D01*
X343793Y-669869D01*
X343393Y-670669D01*
X343093Y-671736D01*
X342993Y-672936D01*
X343093Y-674136D01*
X343393Y-675203D01*
X343793Y-676003D01*
X344393Y-676669D01*
X345193Y-676936D01*
X345993Y-676669D01*
X346593Y-676003D01*
X346993Y-675203D01*
X347293Y-674136D01*
X347393Y-672936D01*
X347293Y-671736D01*
X346993Y-670669D01*
X346593Y-669869D01*
X345993Y-669203D01*
X345193Y-668936D01*
G01X351493Y-676003D02*
X352193Y-676669D01*
X352993Y-676936D01*
X353793Y-676669D01*
X354493Y-675870D01*
X354993Y-674669D01*
X355193Y-673469D01*
Y-672003D01*
X354993Y-670803D01*
X354493Y-669736D01*
X353893Y-669203D01*
X353193Y-668936D01*
X352393Y-669203D01*
X351793Y-669736D01*
X351393Y-670536D01*
X351193Y-671603D01*
X351393Y-672536D01*
X351893Y-673469D01*
X352493Y-674003D01*
X353193Y-674136D01*
X353993Y-673870D01*
X354593Y-673203D01*
X355193Y-672003D01*
G01X278993Y-651936D02*
Y-643936D01*
X280993D01*
X281793Y-644336D01*
X282393Y-644869D01*
X282893Y-645669D01*
X283293Y-646603D01*
X283393Y-647936D01*
X283293Y-649269D01*
X282893Y-650203D01*
X282393Y-651003D01*
X281793Y-651536D01*
X280993Y-651936D01*
X278993D01*
G01X286693D02*
X289193Y-643936D01*
X291693Y-651936D01*
G01X290793Y-649136D02*
X287593D01*
G01X297193Y-643936D02*
X296393Y-644203D01*
X295793Y-644869D01*
X295393Y-645669D01*
X295093Y-646736D01*
X294993Y-647936D01*
X295093Y-649136D01*
X295393Y-650203D01*
X295793Y-651003D01*
X296393Y-651669D01*
X297193Y-651936D01*
X297993Y-651669D01*
X298593Y-651003D01*
X298993Y-650203D01*
X299293Y-649136D01*
X299393Y-647936D01*
X299293Y-646736D01*
X298993Y-645669D01*
X298593Y-644869D01*
X297993Y-644203D01*
X297193Y-643936D01*
G01X303293Y-651936D02*
Y-643936D01*
X307093D01*
G01X305693Y-647803D02*
X303293D01*
G01X313193Y-643936D02*
X312393Y-644203D01*
X311793Y-644869D01*
X311393Y-645669D01*
X311093Y-646736D01*
X310993Y-647936D01*
X311093Y-649136D01*
X311393Y-650203D01*
X311793Y-651003D01*
X312393Y-651669D01*
X313193Y-651936D01*
X313993Y-651669D01*
X314593Y-651003D01*
X314993Y-650203D01*
X315293Y-649136D01*
X315393Y-647936D01*
X315293Y-646736D01*
X314993Y-645669D01*
X314593Y-644869D01*
X313993Y-644203D01*
X313193Y-643936D01*
G01X321193D02*
Y-651936D01*
G01X318893Y-643936D02*
X323493D01*
G01X326593Y-651936D02*
Y-643936D01*
X329193Y-650603D01*
X331793Y-643936D01*
Y-651936D01*
G01X334993D02*
Y-643936D01*
X336993D01*
X337793Y-644336D01*
X338393Y-644869D01*
X338893Y-645669D01*
X339293Y-646603D01*
X339393Y-647936D01*
X339293Y-649269D01*
X338893Y-650203D01*
X338393Y-651003D01*
X337793Y-651536D01*
X336993Y-651936D01*
X334993D01*
G01X347393Y-644603D02*
X346793Y-644203D01*
X346093Y-643936D01*
X345293D01*
X344393Y-644336D01*
X343693Y-645003D01*
X343193Y-645803D01*
X342793Y-647136D01*
X342693Y-648336D01*
X342893Y-649536D01*
X343193Y-650336D01*
X343793Y-651136D01*
X344493Y-651669D01*
X345193Y-651936D01*
X345893D01*
X346593Y-651669D01*
X347193Y-651269D01*
X347693Y-650736D01*
G01X350993Y-651936D02*
Y-643936D01*
X352993D01*
X353793Y-644336D01*
X354393Y-644869D01*
X354893Y-645669D01*
X355293Y-646603D01*
X355393Y-647936D01*
X355293Y-649269D01*
X354893Y-650203D01*
X354393Y-651003D01*
X353793Y-651536D01*
X352993Y-651936D01*
X350993D01*
G01X361193Y-643936D02*
X360393Y-644203D01*
X359793Y-644869D01*
X359393Y-645669D01*
X359093Y-646736D01*
X358993Y-647936D01*
X359093Y-649136D01*
X359393Y-650203D01*
X359793Y-651003D01*
X360393Y-651669D01*
X361193Y-651936D01*
X361993Y-651669D01*
X362593Y-651003D01*
X362993Y-650203D01*
X363293Y-649136D01*
X363393Y-647936D01*
X363293Y-646736D01*
X362993Y-645669D01*
X362593Y-644869D01*
X361993Y-644203D01*
X361193Y-643936D01*
G01X298418Y-624819D02*
Y-618519D01*
X301394D01*
G01X300298Y-621564D02*
X298418D01*
G01X306206Y-618519D02*
X305579Y-618729D01*
X305109Y-619254D01*
X304796Y-619884D01*
X304561Y-620724D01*
X304483Y-621669D01*
X304561Y-622614D01*
X304796Y-623454D01*
X305109Y-624084D01*
X305579Y-624609D01*
X306206Y-624819D01*
X306833Y-624609D01*
X307303Y-624084D01*
X307616Y-623454D01*
X307851Y-622614D01*
X307929Y-621669D01*
X307851Y-620724D01*
X307616Y-619884D01*
X307303Y-619254D01*
X306833Y-618729D01*
X306206Y-618519D01*
G01X312506D02*
Y-624819D01*
G01X310704Y-618519D02*
X314308D01*
G01X316456Y-626919D02*
X321156D01*
G01X323069Y-624819D02*
Y-618519D01*
X325106Y-623769D01*
X327143Y-618519D01*
Y-624819D01*
G01X332816D02*
Y-620619D01*
G01Y-621354D02*
X332503Y-620934D01*
X332033Y-620724D01*
X331484Y-620619D01*
X330936Y-620829D01*
X330466Y-621249D01*
X330153Y-621879D01*
X329996Y-622719D01*
X330153Y-623559D01*
X330466Y-624189D01*
X330936Y-624609D01*
X331484Y-624819D01*
X332033Y-624714D01*
X332503Y-624399D01*
X332816Y-623979D01*
G01X336374Y-624819D02*
Y-620619D01*
G01Y-621669D02*
X336688Y-621144D01*
X337158Y-620724D01*
X337784Y-620619D01*
X338333Y-620724D01*
X338803Y-621144D01*
X339038Y-621879D01*
Y-624819D01*
G01X345416D02*
Y-620619D01*
G01Y-621354D02*
X345103Y-620934D01*
X344633Y-620724D01*
X344084Y-620619D01*
X343536Y-620829D01*
X343066Y-621249D01*
X342753Y-621879D01*
X342596Y-622719D01*
X342753Y-623559D01*
X343066Y-624189D01*
X343536Y-624609D01*
X344084Y-624819D01*
X344633Y-624714D01*
X345103Y-624399D01*
X345416Y-623979D01*
G01X349209Y-626394D02*
X349758Y-626814D01*
X350384Y-626919D01*
X350933Y-626814D01*
X351403Y-626289D01*
X351716Y-625554D01*
Y-620619D01*
G01Y-621459D02*
X351403Y-621039D01*
X350933Y-620724D01*
X350384Y-620619D01*
X349758Y-620829D01*
X349366Y-621249D01*
X349053Y-621984D01*
X348896Y-622719D01*
X348974Y-623349D01*
X349288Y-624084D01*
X349758Y-624609D01*
X350384Y-624819D01*
X350854Y-624714D01*
X351403Y-624294D01*
X351716Y-623874D01*
G01X355431Y-621984D02*
X357938D01*
X357703Y-621249D01*
X357311Y-620829D01*
X356763Y-620619D01*
X356214Y-620724D01*
X355744Y-621039D01*
X355431Y-621774D01*
X355274Y-622404D01*
Y-623034D01*
X355431Y-623664D01*
X355823Y-624294D01*
X356293Y-624714D01*
X356841Y-624819D01*
X357389Y-624609D01*
X357938Y-623979D01*
G01X360556Y-624819D02*
Y-620619D01*
G01Y-621774D02*
X360791Y-621249D01*
X361183Y-620829D01*
X361731Y-620619D01*
X362279Y-620829D01*
X362671Y-621249D01*
X362906Y-621774D01*
Y-624819D01*
G01Y-621774D02*
X363141Y-621249D01*
X363533Y-620829D01*
X364081Y-620619D01*
X364629Y-620829D01*
X365021Y-621249D01*
X365256Y-621879D01*
Y-624819D01*
G01X368031Y-621984D02*
X370538D01*
X370303Y-621249D01*
X369911Y-620829D01*
X369363Y-620619D01*
X368814Y-620724D01*
X368344Y-621039D01*
X368031Y-621774D01*
X367874Y-622404D01*
Y-623034D01*
X368031Y-623664D01*
X368423Y-624294D01*
X368893Y-624714D01*
X369441Y-624819D01*
X369989Y-624609D01*
X370538Y-623979D01*
G01X374174Y-624819D02*
Y-620619D01*
G01Y-621669D02*
X374488Y-621144D01*
X374958Y-620724D01*
X375584Y-620619D01*
X376133Y-620724D01*
X376603Y-621144D01*
X376838Y-621879D01*
Y-624819D01*
G01X381806Y-618519D02*
Y-624819D01*
G01X380709Y-620619D02*
X382903D01*
G01X385756Y-626919D02*
X390456D01*
G01X395033Y-621459D02*
X395346Y-621144D01*
X395581Y-620619D01*
X395738Y-619884D01*
X395581Y-619254D01*
X395268Y-618834D01*
X394719Y-618519D01*
X392604D01*
Y-624819D01*
X395189D01*
X395738Y-624399D01*
X396051Y-623769D01*
X396208Y-623034D01*
X396051Y-622299D01*
X395581Y-621669D01*
X395033Y-621459D01*
X392604D01*
G01X398983Y-624819D02*
Y-618519D01*
X400549D01*
X401176Y-618834D01*
X401646Y-619254D01*
X402038Y-619884D01*
X402351Y-620619D01*
X402429Y-621669D01*
X402351Y-622719D01*
X402038Y-623454D01*
X401646Y-624084D01*
X401176Y-624504D01*
X400549Y-624819D01*
X398983D01*
G01X367693Y-679936D02*
Y-671936D01*
X366493Y-673536D01*
G01Y-679936D02*
X368893D01*
G01X373793Y-676603D02*
X374493Y-675669D01*
X375093Y-675136D01*
X375893Y-674869D01*
X376593Y-675136D01*
X377093Y-675669D01*
X377493Y-676469D01*
X377593Y-677403D01*
X377493Y-678203D01*
X377093Y-679003D01*
X376493Y-679669D01*
X375793Y-679936D01*
X374993Y-679669D01*
X374293Y-678870D01*
X373893Y-677669D01*
X373793Y-676336D01*
X373993Y-674603D01*
X374293Y-673669D01*
X374793Y-672736D01*
X375493Y-672069D01*
X376193Y-671936D01*
X376893Y-672203D01*
X377393Y-672869D01*
G01X383693Y-680203D02*
X383493Y-680069D01*
Y-679803D01*
X383693Y-679669D01*
X383893Y-679803D01*
Y-680069D01*
X383693Y-680203D01*
G01X389793Y-676603D02*
X390493Y-675669D01*
X391093Y-675136D01*
X391893Y-674869D01*
X392593Y-675136D01*
X393093Y-675669D01*
X393493Y-676469D01*
X393593Y-677403D01*
X393493Y-678203D01*
X393093Y-679003D01*
X392493Y-679669D01*
X391793Y-679936D01*
X390993Y-679669D01*
X390293Y-678870D01*
X389893Y-677669D01*
X389793Y-676336D01*
X389993Y-674603D01*
X390293Y-673669D01*
X390793Y-672736D01*
X391493Y-672069D01*
X392193Y-671936D01*
X392893Y-672203D01*
X393393Y-672869D01*
G01X412693Y-679936D02*
Y-671936D01*
X411493Y-673536D01*
G01Y-679936D02*
X413893D01*
G01X420493D02*
X420693Y-678203D01*
X420993Y-676736D01*
X421393Y-675403D01*
X421893Y-673936D01*
X422693Y-671936D01*
X418693D01*
G01X428693Y-680203D02*
X428493Y-680069D01*
Y-679803D01*
X428693Y-679669D01*
X428893Y-679803D01*
Y-680069D01*
X428693Y-680203D01*
G01X434793Y-673269D02*
X435393Y-672469D01*
X436093Y-672069D01*
X436893Y-671936D01*
X437893Y-672203D01*
X438593Y-672869D01*
X438793Y-673669D01*
X438693Y-674470D01*
X438293Y-675136D01*
X436293Y-676469D01*
X435393Y-677403D01*
X434793Y-678736D01*
X434593Y-679936D01*
X438793D01*
G01X432493Y-654936D02*
Y-646936D01*
X434493D01*
X435293Y-647336D01*
X435893Y-647869D01*
X436393Y-648669D01*
X436793Y-649603D01*
X436893Y-650936D01*
X436793Y-652269D01*
X436393Y-653203D01*
X435893Y-654003D01*
X435293Y-654536D01*
X434493Y-654936D01*
X432493D01*
M02*
